FILE_TYPE = MULTI_PHYS_TABLE;

PART 'Q_INDUCTOR'

{========================================================================================}
:VALUE                          | PACK_TYPE  | MATERIAL | PART_NUMBER                = STANDARD        | LIFECYCLE          | PART_NUMBER                | JEDEC_TYPE                        | VALUE                          | CLASS      | DESCRIPTION                                     | COMPONENT_TYPE | LEAD_LENGTH | LPID | DAY          ;
{========================================================================================}
 '0.2UH'                        | 'TH'       | 'IND'    | 'TMP_QDC+20K0M000'(!)      = 'Non-Preferred' | 'End of Life'      | 'DC+20K0M000'              |'LC7_P8XA_EOL'| '0.2UH'                        | 'DISCRETE' | 'INDUCTOR 0.2UH'                                | 'THMT'         | ''          | ''   | ''          
 '0.2UH'                        | 'TH'       | 'EMPTY'  | 'TMP_QDC+20K0M000'(!)      = 'Non-Preferred' | 'End of Life'      | 'DC+20K0M000'              |'LC7_P8XA_EOL'| 'NA'                           | 'IO'       | 'INDUCTOR 0.2UH'                                | 'THMT'         | ''          | ''   | ''          
 '0.2UH'                        | 'TH_SEL'   | 'IND'    | 'TMP_QDC+20K0M000'(!)      = 'Non-Preferred' | 'End of Life'      | 'DC+20K0M000'              |'G_LC7_P8XA_I_T2B_EOL'| '0.2UH'                        | 'DISCRETE' | 'INDUCTOR 0.2UH'                                | 'THMT'         | ''          | ''   | '20100820'  
 '0.2UH'                        | 'TH_SEL'   | 'EMPTY'  | 'TMP_QDC+20K0M000'(!)      = 'Non-Preferred' | 'End of Life'      | 'DC+20K0M000'              |'G_LC7_P8XA_I_T2B_EOL'| 'NA'                           | 'IO'       | 'INDUCTOR 0.2UH'                                | 'THMT'         | ''          | ''   | '20100820'  
 '10UH'                         | 'SMLF'     | 'IND'    | 'TMP_QCV01001MZ02'(!)      = 'End of Design' | 'Comp-Approve'     | 'CV01001MZ02'              |'L0603'| '10UH'                         | 'DISCRETE' | 'INDUCTOR 10UH'                                 | 'CHIP0603'     | ''          | ''   | ''          
 '10UH'                         | 'SMLF'     | 'EMPTY'  | 'TMP_QCV01001MZ02'(!)      = 'End of Design' | 'Comp-Approve'     | 'CV01001MZ02'              |'L0603'| 'NA'                           | 'IO'       | 'INDUCTOR 10UH'                                 | 'CHIP0603'     | ''          | ''   | ''          
 'BLM31PG601SN1L'               | 'SMLF'     | 'IND'    | 'TMP_QCX1PG601016'(!)      = ''              | ''                 | 'CX1PG601016'              |'L1206'| 'BLM31PG601SN1L'               | 'DISCRETE' | 'BLM31PG601SN1L'                                | 'CHIP'         | ''          | ''   | ''          
 'BLM31PG601SN1L'               | 'SMLF'     | 'EMPTY'  | 'TMP_QCX1PG601016'(!)      = ''              | ''                 | 'CX1PG601016'              |'L1206'| 'NA'                           | 'IO'       | 'BLM31PG601SN1L'                                | 'CHIP'         | ''          | ''   | ''          
 '1.8UH'                        | 'SMLF'     | 'IND'    | 'TMP_QDC-18K0M000'(!)      = ''              | ''                 | 'DC-18K0M000'              |'LC16-5_P6XA'| '1.8UH'                        | 'DISCRETE' | 'CHOKE 1.8U 20A+-20%(WM44SF36Q-110109Y-U)'      | 'THMT'         | ''          | ''   | ''          
 '1.8UH'                        | 'SMLF'     | 'EMPTY'  | 'TMP_QDC-18K0M000'(!)      = ''              | ''                 | 'DC-18K0M000'              |'LC16-5_P6XA'| 'NA'                           | 'IO'       | 'CHOKE 1.8U 20A+-20%(WM44SF36Q-110109Y-U)'      | 'THMT'         | ''          | ''   | ''          
 '0.33UH'                       | 'SMLF'     | 'IND'    | 'TMP_QCV+33K0MZ28'(!)      = 'End of Design' | 'End of Life'      | 'CV+33K0MZ28'              |'L_MPL73_EOL'| '0.33UH'                       | 'DISCRETE' | 'IND 0.33UH +-20% 20A( MPL73-R33)'              | 'CHIP'         | ''          | ''   | ''          
 '0.33UH'                       | 'SMLF'     | 'EMPTY'  | 'TMP_QCV+33K0MZ28'(!)      = 'End of Design' | 'End of Life'      | 'CV+33K0MZ28'              |'L_MPL73_EOL'| 'NA'                           | 'IO'       | 'IND 0.33UH +-20% 20A( MPL73-R33)'              | 'CHIP'         | ''          | ''   | ''          
 '3.3UH'                        | 'SMLF'     | 'IND'    | 'TMP_QCV-3383MZ01'(!)      = ''              | ''                 | 'CV-3383MZ01'              |'L_KJ07XA'| '3.3UH'                        | 'DISCRETE' | 'IND SMD 3.3UH+-20% 8.3A(KJ0760-3R3M)'          | 'CHIP'         | ''          | ''   | ''          
 '3.3UH'                        | 'SMLF'     | 'EMPTY'  | 'TMP_QCV-3383MZ01'(!)      = ''              | ''                 | 'CV-3383MZ01'              |'L_KJ07XA'| 'NA'                           | 'IO'       | 'IND SMD 3.3UH+-20% 8.3A(KJ0760-3R3M)'          | 'CHIP'         | ''          | ''   | ''          
 '7UH'                          | 'SMLF'     | 'IND'    | 'TMP_QCV-7048TZ25'(!)      = 'End of Design' | 'End of Life'      | 'CV-7048TZ25'              |'L_SIL104R_EOL'| '7UH'                          | 'DISCRETE' | 'IND SMD 7.0UH 30% 4.8A(SIL104R-7R0PF)L-F'      | 'CHIP'         | ''          | ''   | ''          
 '7UH'                          | 'SMLF'     | 'EMPTY'  | 'TMP_QCV-7048TZ25'(!)      = 'End of Design' | 'End of Life'      | 'CV-7048TZ25'              |'L_SIL104R_EOL'| 'NA'                           | 'IO'       | 'IND SMD 7.0UH 30% 4.8A(SIL104R-7R0PF)L-F'      | 'CHIP'         | ''          | ''   | ''          
 'BLM18PG181SN1D'               | 'SMLF'     | 'IND'    | 'TMP_QCX8PG181001'(!)      = 'End of Design' | 'Comp-Approve'     | 'CX8PG181001'              |'L0603'| 'BLM18PG181SN1D'               | 'DISCRETE' | 'EMI FILTER BLM18PG181SN1D(180,1500MA)'         | 'CHIP'         | ''          | ''   | ''          
 'BLM18PG181SN1D'               | 'SMLF'     | 'EMPTY'  | 'TMP_QCX8PG181001'(!)      = 'End of Design' | 'Comp-Approve'     | 'CX8PG181001'              |'L0603'| 'NA'                           | 'IO'       | 'IND SMD 7.0UH 30% 4.8A(SIL104R-7R0PF)L-F'      | 'CHIP'         | ''          | ''   | ''          
 '1.2UH'                        | 'SMLF'     | 'IND'    | 'TMP_QDC-12^0M002'(!)      = ''              | ''                 | 'DC-12^0M002'              |'LC18_P7-5B'| '1.2UH'                        | 'DISCRETE' | 'CHOKE 1.2U+-20% 40A(APU105014008P-1R2MU)'      | 'CHIP'         | ''          | ''   | ''          
 '1.2UH'                        | 'SMLF'     | 'EMPTY'  | 'TMP_QDC-12^0M002'(!)      = ''              | ''                 | 'DC-12^0M002'              |'LC18_P7-5B'| 'NA'                           | 'IO'       | 'CHOKE 1.2U+-20% 40A(APU105014008P-1R2MU)'      | 'CHIP'         | ''          | ''   | ''          
 '2.5UH'                        | 'SMLF'     | 'IND'    | 'TMP_QCV-2575MZ02'(!)      = ''              | ''                 | 'CV-2575MZ02'              |'L_MSCDRI104R'| '2.5UH'                        | 'DISCRETE' | 'IND SMD 2.5U 20%7.5A(MSCDRI-104R-2R5M)'        | 'CHIP'         | ''          | ''   | ''          
 '2.5UH'                        | 'SMLF'     | 'EMPTY'  | 'TMP_QCV-2575MZ02'(!)      = ''              | ''                 | 'CV-2575MZ02'              |'L_MSCDRI104R'| 'NA'                           | 'IO'       | 'IND SMD 2.5U 20%7.5A(MSCDRI-104R-2R5M)'        | 'CHIP'         | ''          | ''   | ''          
 '7UH'                          | 'SMLF'     | 'IND'    | 'TMP_QCV-7048MZ01'(!)      = ''              | ''                 | 'CV-7048MZ01'              |'L_MSCDRI104R'| '7UH'                          | 'DISCRETE' | 'IND SMD 7UH 20% 4.8A(MSCDRI-104R-7R0M)'        | 'CHIP'         | ''          | ''   | ''          
 '7UH'                          | 'SMLF'     | 'EMPTY'  | 'TMP_QCV-7048MZ01'(!)      = ''              | ''                 | 'CV-7048MZ01'              |'L_MSCDRI104R'| 'NA'                           | 'IO'       | 'IND SMD 7UH 20% 4.8A(MSCDRI-104R-7R0M)'        | 'CHIP'         | ''          | ''   | ''          
 '1.8UH'                        | 'SMLF'     | 'IND'    | 'TMP_QDC-18K0M002'(!)      = ''              | ''                 | 'DC-18K0M002'              |'LC15_P6A'| '1.8UH'                        | 'DISCRETE' | 'CHOKE 1.8U 20A+-20%(APU104417010P-1R8MU)'      | 'CHIP'         | ''          | ''   | ''          
 '1.8UH'                        | 'SMLF'     | 'EMPTY'  | 'TMP_QDC-18K0M002'(!)      = ''              | ''                 | 'DC-18K0M002'              |'LC15_P6A'| 'NA'                           | 'IO'       | 'CHOKE 1.8U 20A+-20%(APU104417010P-1R8MU)'      | 'CHIP'         | ''          | ''   | ''          
 '3.3UH'                        | 'SMLF'     | 'IND'    | 'TMP_QCV-3321MZ00'(!)      = ''              | ''                 | 'CV-3321MZ00'              |'L_MSCD43'| '3.3UH'                        | 'DISCRETE' | 'IND SMD 3.3UH,+-20% 2.15A(FPI0403)'            | 'CHIP'         | ''          | ''   | ''          
 '3.3UH'                        | 'SMLF'     | 'EMPTY'  | 'TMP_QCV-3321MZ00'(!)      = ''              | ''                 | 'CV-3321MZ00'              |'L_MSCD43'| 'NA'                           | 'IO'       | 'IND SMD 3.3UH,+-20% 2.15A(FPI0403)'            | 'CHIP'         | ''          | ''   | ''          
 '0.4UH'                        | 'THLF'     | 'IND'    | 'TMP_QDC+40K0M009'(!)      = 'Non-Preferred' | 'End of Life'      | 'DC+40K0M009'              |'LC12_P8_EOL'| '0.4UH'                        | 'DISCRETE' | 'CHOKE 0.4U 20A+-20%(WR0412)'                   | 'CHIP'         | ''          | ''   | ''          
 '0.4UH'                        | 'THLF'     | 'EMPTY'  | 'TMP_QDC+40K0M009'(!)      = 'Non-Preferred' | 'End of Life'      | 'DC+40K0M009'              |'LC12_P8_EOL'| 'NA'                           | 'IO'       | 'CHOKE 0.4U 20A+-20%(WR0412)'                   | 'CHIP'         | ''          | ''   | ''          
 '4.7UH'                        | 'THLF'     | 'IND'    | 'TMP_QCV-47A0MD00'(!)      = ''              | ''                 | 'CV-47A0MD00'              |'LC10_P8XA'| '4.7UH'                        | 'DISCRETE' | 'IND DIP 4.7U +-20%,10A(KQ10VC-4R7M)'           | 'CHIP'         | ''          | ''   | ''          
 '4.7UH'                        | 'THLF'     | 'EMPTY'  | 'TMP_QCV-47A0MD00'(!)      = ''              | ''                 | 'CV-47A0MD00'              |'LC10_P8XA'| 'NA'                           | 'IO'       | 'IND DIP 4.7U +-20%,10A(KQ10VC-4R7M)'           | 'CHIP'         | ''          | ''   | ''          
 'HB-1S1005-100JT'              | 'SMLF'     | 'IND'    | 'TMP_QCX0100JT000'(!)      = 'End of Design' | 'Comp-Approve'     | 'CX0100JT000'              |'L0402'| 'HB-1S1005-100JT'              | 'DISCRETE' | 'EMI FILTER HB-1S1005-100JT(10,500MA)'          | 'CHIP'         | ''          | ''   | ''          
 'HB-1S1005-100JT'              | 'SMLF'     | 'EMPTY'  | 'TMP_QCX0100JT000'(!)      = 'End of Design' | 'Comp-Approve'     | 'CX0100JT000'              |'L0402'| 'NA'                           | 'IO'       | 'EMI FILTER HB-1S1005-100JT(10,500MA)'          | 'CHIP'         | ''          | ''   | ''          
 'SBK160808T-100Y-N'            | 'SMLF'     | 'IND'    | 'TMP_QCX08T100001'(!)      = ''              | ''                 | 'CX08T100001'              |'L0603'| 'SBK160808T-100Y-N'            | 'DISCRETE' | 'EMI FILTER SBK160808T-100Y-N(10,500MA)'        | 'CHIP'         | ''          | ''   | ''          
 'SBK160808T-100Y-N'            | 'SMLF'     | 'EMPTY'  | 'TMP_QCX08T100001'(!)      = ''              | ''                 | 'CX08T100001'              |'L0603'| 'NA'                           | 'IO'       | 'EMI FILTER SBK160808T-100Y-N(10,500MA)'        | 'CHIP'         | ''          | ''   | ''          
 '0.45UH'                       | 'SMLF'     | 'IND'    | 'TMP_QCV+45^0MZ05'(!)      = ''              | ''                 | 'CV+45^0MZ05'              |'L_SIHH1309'| '0.45UH'                       | 'DISCRETE' | 'IND SMD 0.45U 20% 45A(SIHH1309-R45M)'          | 'CHIP'         | ''          | ''   | ''          
 '0.45UH'                       | 'SMLF'     | 'EMPTY'  | 'TMP_QCV+45^0MZ05'(!)      = ''              | ''                 | 'CV+45^0MZ05'              |'L_SIHH1309'| 'NA'                           | 'IO'       | 'IND SMD 0.45U 20% 45A(SIHH1309-R45M)'          | 'CHIP'         | ''          | ''   | ''          
 'BLM15HD182SN1D'               | 'SMLF'     | 'IND'    | 'TMP_QCX5HD182000'(!)      = ''              | ''                 | 'CX5HD182000'              |'L0402'| '1800'                         | 'DISCRETE' | 'EMI FILTER BLM15HD182SN1D(1800,200MA)'         | 'CHIP'         | ''          | ''   | ''          
 'BLM15HD182SN1D'               | 'SMLF'     | 'EMPTY'  | 'TMP_QCX5HD182000'(!)      = ''              | ''                 | 'CX5HD182000'              |'L0402'| 'NA'                           | 'IO'       | 'EMI FILTER BLM15HD182SN1D(1800,200MA)'         | 'CHIP'         | ''          | ''   | ''          
 'MPZ2012S331ATA'               | 'SMLF'     | 'IND'    | 'TMP_QCX12S331006'(!)      = 'End of Design' | 'End of Life'      | 'CX12S331006'              |'L0805_EOL'| '330'                          | 'DISCRETE' | 'EMI FIL CHIP MPZ2012S331ATA(330,2.5A)'         | 'CHIP'         | ''          | ''   | ''          
 'MPZ2012S331ATA'               | 'SMLF'     | 'EMPTY'  | 'TMP_QCX12S331006'(!)      = 'End of Design' | 'End of Life'      | 'CX12S331006'              |'L0805_EOL'| 'NA'                           | 'IO'       | 'EMI FIL CHIP MPZ2012S331ATA(330,2.5A)'         | 'CHIP'         | ''          | ''   | ''          
 'MPZ2012S101AT'                | 'SMLF'     | 'IND'    | 'TMP_QCX12S101001'(!)      = 'End of Design' | 'End of Life'      | 'CX12S101001'              |'L0805_EOL'| '100'                          | 'DISCRETE' | 'EMI FIL CHIP MPZ2012S101AT(100,4A)L-F'         | 'CHIP'         | ''          | ''   | ''          
 'MPZ2012S101AT'                | 'SMLF'     | 'EMPTY'  | 'TMP_QCX12S101001'(!)      = 'End of Design' | 'End of Life'      | 'CX12S101001'              |'L0805_EOL'| 'NA'                           | 'IO'       | 'EMI FIL CHIP MPZ2012S101AT(100,4A)L-F'         | 'CHIP'         | ''          | ''   | ''          
 'BLM18BD601SN1D'               | 'SMLF'     | 'IND'    | 'TMP_QCX8BD601001'(!)      = ''              | ''                 | 'CX8BD601001'              |'L0603'| 'BLM18BD601SN1D'               | 'DISCRETE' | 'EMI FILTER CHIP BLM18BD601SN1D(0603)'          | 'CHIP'         | ''          | ''   | ''          
 'BLM18BD601SN1D'               | 'SMLF'     | 'EMPTY'  | 'TMP_QCX8BD601001'(!)      = ''              | ''                 | 'CX8BD601001'              |'L0603'| 'NA'                           | 'IO'       | 'EMI FILTER CHIP BLM18BD601SN1D(0603)'          | 'CHIP'         | ''          | ''   | ''          
 'BLM18PG300SN1D '              | 'SMLF'     | 'IND'    | 'TMP_QCX8PG300001'(!)      = ''              | ''                 | 'CX8PG300001'              |'L0603'| 'BLM18PG300SN1D '              | 'DISCRETE' | 'EMI FILTER SBK160808T-100Y-N(10,500MA)'        | 'CHIP'         | ''          | ''   | ''          
 'BLM18PG300SN1D '              | 'SMLF'     | 'EMPTY'  | 'TMP_QCX8PG300001'(!)      = ''              | ''                 | 'CX8PG300001'              |'L0603'| 'NA'                           | 'IO'       | 'EMI FILTER SBK160808T-100Y-N(10,500MA)'        | 'CHIP'         | ''          | ''   | ''          
 '4.7UH '                       | 'SMLF'     | 'IND'    | 'TMP_QCV-4706MZ00'(!)      = ''              | ''                 | 'CV-4706MZ00'              |'L1007XA'| '4.7UH '                       | 'DISCRETE' | 'IND SMD 4.7UH 20% 510MA'                       | 'CHIP'         | ''          | ''   | ''          
 '4.7UH '                       | 'SMLF'     | 'EMPTY'  | 'TMP_QCV-4706MZ00'(!)      = ''              | ''                 | 'CV-4706MZ00'              |'L1007XA'| 'NA'                           | 'IO'       | 'IND SMD 4.7UH 20% 510MA'                       | 'CHIP'         | ''          | ''   | ''          
 '0.88UH'                       | 'SMLF'     | 'IND'    | 'TMP_QDC+88K0M009'(!)      = 'Standard'      | 'End of Life'      | 'DC+88K0M009'              |'L_PCMC104T_EOL'| '0.88UH'                       | 'DISCRETE' | 'CHOKE COIL 0.88UH,20%20A(PCMC104T-R88MN)'      | 'CHIP'         | ''          | ''   | ''          
 '0.88UH'                       | 'SMLF'     | 'EMPTY'  | 'TMP_QDC+88K0M009'(!)      = 'Standard'      | 'End of Life'      | 'DC+88K0M009'              |'L_PCMC104T_EOL'| 'NA'                           | 'IO'       | 'CHOKE COIL 0.88UH,20%20A(PCMC104T-R88MN)'      | 'CHIP'         | ''          | ''   | ''          
 '10UH'                         | 'SMLF'     | 'IND'    | 'TMP_QCV01005KZ00'(!)      = ''              | ''                 | 'CV01005KZ00'              |'L_1210XA'| '10UH'                         | 'DISCRETE' | 'IND SMD 10U +-10% 450MA(NLCV32T-100K-PF)'      | 'CHIP'         | ''          | ''   | ''          
 '10UH'                         | 'SMLF'     | 'EMPTY'  | 'TMP_QCV01005KZ00'(!)      = ''              | ''                 | 'CV01005KZ00'              |'L_1210XA'| 'NA'                           | 'IO'       | 'IND SMD 10U +-10% 450MA(NLCV32T-100K-PF)'      | 'CHIP'         | ''          | ''   | ''          
 'BLM21AG601SN1D'               | 'SMLF'     | 'IND'    | 'TMP_QCX21AG60008'(!)      = 'End of Design' | 'Comp-Approve'     | 'CX21AG60008'              |'L0805'| 'BLM21AG601SN1D'               | 'DISCRETE' | 'EMI FILTER BLM21AG601SN1D(0.2A,600)'           | 'CHIP'         | ''          | ''   | ''          
 'BLM21AG601SN1D'               | 'SMLF'     | 'EMPTY'  | 'TMP_QCX21AG60008'(!)      = 'End of Design' | 'Comp-Approve'     | 'CX21AG60008'              |'L0805'| 'NA'                           | 'IO'       | 'EMI FILTER BLM21AG601SN1D(0.2A,600)'           | 'CHIP'         | ''          | ''   | ''          
 'BLM18AG601SN1D '              | 'SMLF'     | 'IND'    | 'TMP_QCW8AG601009'(!)      = ''              | 'End of Life'      | 'CW8AG601009'              |'L0603_EOL'| 'BLM18AG601SN1D '              | 'DISCRETE' | 'FERRITE BEAD BLM18AG601SN1D (200M)'            | 'CHIP'         | ''          | ''   | ''          
 'BLM18AG601SN1D '              | 'SMLF'     | 'EMPTY'  | 'TMP_QCW8AG601009'(!)      = ''              | 'End of Life'      | 'CW8AG601009'              |'L0603_EOL'| 'NA'                           | 'IO'       | 'FERRITE BEAD BLM18AG601SN1D (200M)'            | 'CHIP'         | ''          | ''   | ''          
 '1UH'                          | 'SMLF'     | 'IND'    | 'TMP_QCV-10B0MZ02'(!)      = 'End of Design' | 'End of Life'      | 'CV-10B0MZ02'              |'L_MPL73_EOL'| '1UH'                          | 'DISCRETE' | 'CHOKE COIL 0.88UH,20%20A(PCMC104T-R88MN)'      | 'CHIP'         | ''          | ''   | ''          
 '1UH'                          | 'SMLF'     | 'EMPTY'  | 'TMP_QCV-10B0MZ02'(!)      = 'End of Design' | 'End of Life'      | 'CV-10B0MZ02'              |'L_MPL73_EOL'| 'NA'                           | 'IO'       | 'CHOKE COIL 0.88UH,20%20A(PCMC104T-R88MN)'      | 'CHIP'         | ''          | ''   | ''          
 'BLM18PG471SN1D '              | 'SMLF'     | 'IND'    | 'TMP_QCX8PG471000'(!)      = ''              | ''                 | 'CX8PG471000'              |'L0603'| 'BLM18PG471SN1D '              | 'DISCRETE' | 'EMI FILTER BLM18PG471SN1D(470,1000MA)'         | 'CHIP'         | ''          | ''   | ''          
 'BLM18PG471SN1D '              | 'SMLF'     | 'EMPTY'  | 'TMP_QCX8PG471000'(!)      = ''              | ''                 | 'CX8PG471000'              |'L0603'| 'NA'                           | 'IO'       | 'EMI FILTER BLM18PG471SN1D(470,1000MA)'         | 'CHIP'         | ''          | ''   | ''          
 'MI1206K601R-10'               | 'SMLF'     | 'IND'    | 'TMP_QCX0K601R000'(!)      = 'Non-Preferred' | 'End of Life'      | 'CX0K601R000'              |'L1206_EOL'| 'MI1206K601R-10 '              | 'DISCRETE' | 'EMI FILTER MI1206K601R-10 (600,1.5A)'          | 'CHIP'         | ''          | ''   | ''          
 'MI1206K601R-10'               | 'SMLF'     | 'EMPTY'  | 'TMP_QCX0K601R000'(!)      = 'Non-Preferred' | 'End of Life'      | 'CX0K601R000'              |'L1206_EOL'| 'NA'                           | 'IO'       | 'EMI FILTER MI1206K601R-10 (600,1.5A)'          | 'CHIP'         | ''          | ''   | ''          
 'CDRH2D11NP-4R7NC'             | 'SMLF'     | 'IND'    | 'TMP_QCV-4705TZ02'(!)      = ''              | ''                 | 'CV-4705TZ02'              |'L_CDRH2D11NP'| 'CDRH2D11NP-4R7NC '            | 'DISCRETE' | 'IND SMD 4.7U 30% 0.5A(CDRH2D11NP-4R7NC)'       | 'CHIP'         | ''          | ''   | ''          
 'CDRH2D11NP-4R7NC'             | 'SMLF'     | 'EMPTY'  | 'TMP_QCV-4705TZ02'(!)      = ''              | ''                 | 'CV-4705TZ02'              |'L_CDRH2D11NP'| 'NA'                           | 'IO'       | 'IND SMD 4.7U 30% 0.5A(CDRH2D11NP-4R7NC)'       | 'CHIP'         | ''          | ''   | ''          
 'BRC2016T100M'                 | 'SMLF'     | 'IND'    | 'TMP_QCV01005MZ02'(!)      = ''              | ''                 | 'CV01005MZ02'              |'L0806XA'| '10UH '                        | 'DISCRETE' | 'IND SMD 10UH +-20%,0.45A(BRC2016T100M)'        | 'CHIP'         | ''          | ''   | ''          
 'BRC2016T100M'                 | 'SMLF'     | 'EMPTY'  | 'TMP_QCV01005MZ02'(!)      = ''              | ''                 | 'CV01005MZ02'              |'L0806XA'| 'NA'                           | 'IO'       | 'IND SMD 10UH +-20%,0.45A(BRC2016T100M)'        | 'CHIP'         | ''          | ''   | ''          
 'CDRH3D23NP-4R7PC'             | 'SMLF'     | 'IND'    | 'TMP_QCV-4713TZ00'(!)      = ''              | ''                 | 'CV-4713TZ00'              |'L_CDRH3D11-HP_H99'| 'CDRH3D23NP-4R7PC'             | 'DISCRETE' | 'IND SMD 4.7UH +-25% 1.3A(CDRH3D23NP-4R7P'      | 'CHIP'         | ''          | ''   | ''          
 'CDRH3D23NP-4R7PC'             | 'SMLF'     | 'EMPTY'  | 'TMP_QCV-4713TZ00'(!)      = ''              | ''                 | 'CV-4713TZ00'              |'L_CDRH3D11-HP_H99'| 'NA'                           | 'IO'       | 'IND SMD 4.7UH +-25% 1.3A(CDRH3D23NP-4R7P'      | 'CHIP'         | ''          | ''   | ''          
 'CDRH3D23NP-1R0PC'             | 'SMLF'     | 'IND'    | 'TMP_QCV-1028TZ00'(!)      = ''              | ''                 | 'CV-1028TZ00'              |'L_CDRH3D11-HP_H99'| 'CDRH3D23NP-1R0PC'             | 'DISCRETE' | 'IND SMD 1UH +-25% 2.8A(CDRH3D23NP-1R0PC)'      | 'CHIP'         | ''          | ''   | ''          
 'CDRH3D23NP-1R0PC'             | 'SMLF'     | 'EMPTY'  | 'TMP_QCV-1028TZ00'(!)      = ''              | ''                 | 'CV-1028TZ00'              |'L_CDRH3D11-HP_H99'| 'NA'                           | 'IO'       | 'IND SMD 1UH +-25% 2.8A(CDRH3D23NP-1R0PC)'      | 'CHIP'         | ''          | ''   | ''          
 'CDRH3D23NP-2R2PC'             | 'SMLF'     | 'IND'    | 'TMP_QCV-2218TZ00'(!)      = ''              | ''                 | 'CV-2218TZ00'              |'L_CDRH3D11-HP_H99'| 'CDRH3D23NP-2R2PC'             | 'DISCRETE' | 'IND SMD 2.2UH +-25% 1.8A(CDRH3D23NP-2R2P'      | 'CHIP'         | ''          | ''   | ''          
 'CDRH3D23NP-2R2PC'             | 'SMLF'     | 'EMPTY'  | 'TMP_QCV-2218TZ00'(!)      = ''              | ''                 | 'CV-2218TZ00'              |'L_CDRH3D11-HP_H99'| 'NA'                           | 'IO'       | 'IND SMD 2.2UH +-25% 1.8A(CDRH3D23NP-2R2P'      | 'CHIP'         | ''          | ''   | ''          
 '0.015UH'                      | 'SMLF'     | 'IND'    | 'TMP_QCVA1503JN51'(!)      = ''              | ''                 | 'CVA1503JN51'              |'L0402'| '0.015UH'                      | 'DISCRETE' | 'INDUCTOR CHIP 0.015U,+-5%,300MA,0402'          | 'CHIP'         | ''          | ''   | ''          
 '0.015UH'                      | 'SMLF'     | 'EMPTY'  | 'TMP_QCVA1503JN51'(!)      = ''              | ''                 | 'CVA1503JN51'              |'L0402'| 'NA'                           | 'IO'       | 'INDUCTOR CHIP 0.015U,+-5%,300MA,0402'          | 'CHIP'         | ''          | ''   | ''          
 '22NH'                         | 'SMLF'     | 'IND'    | 'TMP_QCVA2203JN02'(!)      = 'Potential'     | 'End of Life'      | 'CVA2203JN02'              |'L0402_EOL'| '22NH'                         | 'DISCRETE' | 'IND CHIP 22N +-5% 300MA,LQG15HS22NJ02D'        | 'CHIP'         | ''          | ''   | ''          
 '22NH'                         | 'SMLF'     | 'EMPTY'  | 'TMP_QCVA2203JN02'(!)      = 'Potential'     | 'End of Life'      | 'CVA2203JN02'              |'L0402_EOL'| 'NA'                           | 'IO'       | 'IND CHIP 22N +-5% 300MA,LQG15HS22NJ02D'        | 'CHIP'         | ''          | ''   | ''          
 'CDRH2D18/HP-4R7NC'            | 'SMLF'     | 'IND'    | 'TMP_QCV-4712TZ00'(!)      = ''              | ''                 | 'CV-4712TZ00'              |'L_CDRH2D11_H79'| 'CDRH2D18/HP-4R7NC '           | 'DISCRETE' | 'IND SMD 4.7U 30% 0.5A(CDRH2D11NP-4R7NC)'       | 'CHIP'         | ''          | ''   | ''          
 'CDRH2D18/HP-4R7NC'            | 'SMLF'     | 'EMPTY'  | 'TMP_QCV-4712TZ00'(!)      = ''              | ''                 | 'CV-4712TZ00'              |'L_CDRH2D11_H79'| 'NA'                           | 'IO'       | 'IND SMD 4.7U 30% 0.5A(CDRH2D11NP-4R7NC)'       | 'CHIP'         | ''          | ''   | ''          
 'BLM21PG600SN1D'               | 'SMLF'     | 'IND'    | 'TMP_QCX1PG600001'(!)      = 'End of Design' | 'Comp-Approve'     | 'CX1PG600001'              |'L0805'| 'BLM21PG600SN1D'               | 'DISCRETE' | 'EMI FILTER CHIP BLM21PG600SN1D(60,3A)'         | 'CHIP'         | ''          | ''   | ''          
 'BLM21PG600SN1D'               | 'SMLF'     | 'EMPTY'  | 'TMP_QCX1PG600001'(!)      = 'End of Design' | 'Comp-Approve'     | 'CX1PG600001'              |'L0805'| 'NA'                           | 'IO'       | 'EMI FILTER CHIP BLM21PG600SN1D(60,3A)'         | 'CHIP'         | ''          | ''   | ''          
 'EPL2010-102MLC'               | 'SMLF'     | 'IND'    | 'TMP_QCV-1010MZ02'(!)      = ''              | ''                 | 'CV-1010MZ02'              |'L_EPL2010'| 'EPL2010-102MLC'               | 'DISCRETE' | 'IND SMD 1U +-20% 1A(EPL2010-102MLC)'           | 'CHIP'         | ''          | ''   | ''          
 'EPL2010-102MLC'               | 'SMLF'     | 'EMPTY'  | 'TMP_QCV-1010MZ02'(!)      = ''              | ''                 | 'CV-1010MZ02'              |'L_EPL2010'| 'NA'                           | 'IO'       | 'IND SMD 1U +-20% 1A(EPL2010-102MLC)'           | 'CHIP'         | ''          | ''   | ''          
 '10UH'                         | 'SMLF'     | 'IND'    | 'TMP_QCV01002MZ01'(!)      = 'End of Design' | 'Comp-Approve'     | 'CV01002MZ01'              |'L0806'| '10UH'                         | 'DISCRETE' | 'IND SMD 10UH,+-20%,155MA(LB2016T100M)'         | 'CHIP'         | ''          | ''   | ''          
 '10UH'                         | 'SMLF'     | 'EMPTY'  | 'TMP_QCV01002MZ01'(!)      = 'End of Design' | 'Comp-Approve'     | 'CV01002MZ01'              |'L0806'| 'NA'                           | 'IO'       | 'IND SMD 10UH,+-20%,155MA(LB2016T100M)'         | 'CHIP'         | ''          | ''   | ''          
 '2700PH'                       | 'SMLF'     | 'IND'    | 'TMP_QCVB27F0TN00'(!)      = 'Potential'     | 'End of Life'      | 'CVB27F0TN00'              |'L0402_EOL'| '47UH'                         | 'DISCRETE' | 'IND CHIP 2700P +-0.2N 15A LQW15AN2N7C00D'      | 'CHIP'         | ''          | ''   | ''          
 '2700PH'                       | 'SMLF'     | 'EMPTY'  | 'TMP_QCVB27F0TN00'(!)      = 'Potential'     | 'End of Life'      | 'CVB27F0TN00'              |'L0402_EOL'| 'NA'                           | 'IO'       | 'IND CHIP 2700P +-0.2N 15A LQW15AN2N7C00D'      | 'CHIP'         | ''          | ''   | ''          
 '4.7UH'                        | 'SMLF'     | 'IND'    | 'TMP_QCV-4714MZ01'(!)      = ''              | ''                 | 'CV-4714MZ01'              |'L_VLF4014S'| '4.7UH'                        | 'DISCRETE' | 'IND SMD 4.7UH +-20% 1.4A VLF4014ST-4R7M1'      | 'CHIP'         | ''          | ''   | ''          
 '4.7UH'                        | 'SMLF'     | 'EMPTY'  | 'TMP_QCV-4714MZ01'(!)      = ''              | ''                 | 'CV-4714MZ01'              |'L_VLF4014S'| 'NA'                           | 'IO'       | 'IND SMD 4.7UH +-20% 1.4A VLF4014ST-4R7M1'      | 'CHIP'         | ''          | ''   | ''          
 '1UH'                          | 'SMLF'     | 'IND'    | 'TMP_QCV-1027TZ00'(!)      = ''              | ''                 | 'CV-1027TZ00'              |'L_VLF4014S'| '1UH'                          | 'DISCRETE' | 'IND SMD 1UH +-30% 2.7A VLF4014ST-1R0N2R3'      | 'CHIP'         | ''          | ''   | ''          
 '1UH'                          | 'SMLF'     | 'EMPTY'  | 'TMP_QCV-1027TZ00'(!)      = ''              | ''                 | 'CV-1027TZ00'              |'L_VLF4014S'| 'NA'                           | 'IO'       | 'IND SMD 1UH +-30% 2.7A VLF4014ST-1R0N2R3'      | 'CHIP'         | ''          | ''   | ''          
 '4.7UH'                        | 'SMLF'     | 'IND'    | 'TMP_QCV-4709MZ00'(!)      = ''              | ''                 | 'CV-4709MZ00'              |'L_VLF3012S'| '4.7UH'                        | 'DISCRETE' | 'IND SMD 4.7UH +-20% 0.91A VLF3012ST-4R7M'      | 'CHIP'         | ''          | ''   | ''          
 '4.7UH'                        | 'SMLF'     | 'EMPTY'  | 'TMP_QCV-4709MZ00'(!)      = ''              | ''                 | 'CV-4709MZ00'              |'L_VLF3012S'| 'NA'                           | 'IO'       | 'IND SMD 4.7UH +-20% 0.91A VLF3012ST-4R7M'      | 'CHIP'         | ''          | ''   | ''          
 '1UH'                          | 'SMLF'     | 'IND'    | 'TMP_QCV-1028TZ02'(!)      = ''              | 'End of Life'      | 'CV-1028TZ02'              |'L_SILM4025_EOL'| '1UH'                          | 'DISCRETE' | 'IND SMD 1UH +-25% 2.8A(SILM4025-1R0-F)'        | 'CHIP'         | ''          | ''   | ''          
 '1UH'                          | 'SMLF'     | 'EMPTY'  | 'TMP_QCV-1028TZ02'(!)      = ''              | 'End of Life'      | 'CV-1028TZ02'              |'L_SILM4025_EOL'| 'NA'                           | 'IO'       | 'IND SMD 1UH +-25% 2.8A(SILM4025-1R0-F)'        | 'CHIP'         | ''          | ''   | ''          
 '4.7UH'                        | 'SMLF'     | 'IND'    | 'TMP_QCV-4713TZ01'(!)      = ''              | 'End of Life'      | 'CV-4713TZ01'              |'L_SILM4025_EOL'| '4.7UH'                        | 'DISCRETE' | 'IND SMD 4.7UH +-25% 1.3A(SILM4025-4R7-F)'      | 'CHIP'         | ''          | ''   | ''          
 '4.7UH'                        | 'SMLF'     | 'EMPTY'  | 'TMP_QCV-4713TZ01'(!)      = ''              | 'End of Life'      | 'CV-4713TZ01'              |'L_SILM4025_EOL'| 'NA'                           | 'IO'       | 'IND SMD 4.7UH +-25% 1.3A(SILM4025-4R7-F)'      | 'CHIP'         | ''          | ''   | ''          
 '4.7UH'                        | 'SMLF'     | 'IND'    | 'TMP_QCV-4712TZ02'(!)      = ''              | 'End of Life'      | 'CV-4712TZ02'              |'L_SILM320A_EOL'| '4.7UH'                        | 'DISCRETE' | 'IND SMD 4.7UH +-25% 1.3A(SILM4025-4R7-F)'      | 'CHIP'         | ''          | ''   | ''          
 '4.7UH'                        | 'SMLF'     | 'EMPTY'  | 'TMP_QCV-4712TZ02'(!)      = ''              | 'End of Life'      | 'CV-4712TZ02'              |'L_SILM320A_EOL'| 'NA'                           | 'IO'       | 'IND SMD 4.7UH +-25% 1.3A(SILM4025-4R7-F)'      | 'CHIP'         | ''          | ''   | ''          
 '4.7UH'                        | 'SMLF'     | 'IND'    | 'TMP_QCV-4717MZ02'(!)      = 'End of Design' | 'Comp-Approve'     | 'CV-4717MZ02'              |'L_NR4018'| '4.7UH'                        | 'DISCRETE' | 'IND SMD 4.7UH +-20% 1700MA(NR4018T4R7M)'       | 'CHIP'         | ''          | ''   | ''          
 '4.7UH'                        | 'SMLF'     | 'EMPTY'  | 'TMP_QCV-4717MZ02'(!)      = 'End of Design' | 'Comp-Approve'     | 'CV-4717MZ02'              |'L_NR4018'| 'NA'                           | 'IO'       | 'IND SMD 4.7UH +-20% 1700MA(NR4018T4R7M)'       | 'CHIP'         | ''          | ''   | ''          
 '1UH'                          | 'SMLF'     | 'IND'    | 'TMP_QCV-1040TZ01'(!)      = ''              | ''                 | 'CV-1040TZ01'              |'L_NR4018'| '1UH'                          | 'DISCRETE' | 'IND SMD 1UH +-30% 4000MA(NR4018T1R0N)'         | 'CHIP'         | ''          | ''   | ''          
 '1UH'                          | 'SMLF'     | 'EMPTY'  | 'TMP_QCV-1040TZ01'(!)      = ''              | ''                 | 'CV-1040TZ01'              |'L_NR4018'| 'NA'                           | 'IO'       | 'IND SMD 1UH +-30% 4000MA(NR4018T1R0N)'         | 'CHIP'         | ''          | ''   | ''          
 'BLM18BD331SN1D'               | 'SMLF'     | 'IND'    | 'TMP_QCX8BD331004'(!)      = ''              | ''                 | 'CX8BD331004'              |'L0603'| 'BLM18BD331SN1D'               | 'DISCRETE' | 'EMI FILTER BLM18BD331SN1D(330,200MA)LF'        | 'CHIP'         | ''          | ''   | ''          
 'BLM18BD331SN1D'               | 'SMLF'     | 'EMPTY'  | 'TMP_QCX8BD331004'(!)      = ''              | ''                 | 'CX8BD331004'              |'L0603'| 'NA'                           | 'IO'       | 'EMI FILTER BLM18BD331SN1D(330,200MA)LF'        | 'CHIP'         | ''          | ''   | ''          
 '0.20UH'                       | 'SMLF'     | 'IND'    | 'TMP_QCV+20^0MZ01'(!)      = 'Non-Preferred' | 'End of Life'      | 'CV+20^0MZ01'              |'L_SIHH0606-R20M_EOL'| '0.20UH'                       | 'DISCRETE' | 'IND SMD 0.2UH,+-20%,35A(SIHC060675-R20M'       | 'CHIP'         | ''          | ''   | ''          
 '0.20UH'                       | 'SMLF'     | 'EMPTY'  | 'TMP_QCV+20^0MZ01'(!)      = 'Non-Preferred' | 'End of Life'      | 'CV+20^0MZ01'              |'L_SIHH0606-R20M_EOL'| 'NA'                           | 'IO'       | 'IND SMD 0.2UH,+-20%,35A(SIHC060675-R20M'       | 'CHIP'         | ''          | ''   | ''          
 '1.5UH'                        | 'SMLF'     | 'IND'    | 'TMP_QCV-15S0MZ15'(!)      = ''              | 'End of Life'      | 'CV-15S0MZ15'              |'L_MPL135_EOL'| '1.5UH'                        | 'DISCRETE' | 'IND SMD 1.5UH 20% 27A(MPL135-1R5)'             | 'CHIP'         | ''          | ''   | ''          
 '1.5UH'                        | 'SMLF'     | 'EMPTY'  | 'TMP_QCV-15S0MZ15'(!)      = ''              | 'End of Life'      | 'CV-15S0MZ15'              |'L_MPL135_EOL'| 'NA'                           | 'IO'       | 'IND SMD 1.5UH 20% 27A(MPL135-1R5)'             | 'CHIP'         | ''          | ''   | ''          
 '4.7UH'                        | 'SMLF'     | 'IND'    | 'TMP_QCV-47A0MZ04'(!)      = ''              | ''                 | 'CV-47A0MZ04'              |'L_MMD-06CZ'| '4.7UH'                        | 'DISCRETE' | 'IND SMD 4.7UH +-20%10A(MMD-06CZ-4R7M)'         | 'CHIP'         | ''          | ''   | ''          
 '4.7UH'                        | 'SMLF'     | 'EMPTY'  | 'TMP_QCV-47A0MZ04'(!)      = ''              | ''                 | 'CV-47A0MZ04'              |'L_MMD-06CZ'| 'NA'                           | 'IO'       | 'IND SMD 4.7UH +-20%10A(MMD-06CZ-4R7M)'         | 'CHIP'         | ''          | ''   | ''          
 '3.3UH'                        | 'SMLF'     | 'IND'    | 'TMP_QCV-3360MZ01'(!)      = ''              | ''                 | 'CV-3360MZ01'              |'L_MMD-06CZ'| '3.3UH'                        | 'DISCRETE' | 'IND SMD 3.3UH20%6A(MMD-06CZ-3R3M-V1W)'         | 'CHIP'         | ''          | ''   | ''          
 '3.3UH'                        | 'SMLF'     | 'EMPTY'  | 'TMP_QCV-3360MZ01'(!)      = ''              | ''                 | 'CV-3360MZ01'              |'L_MMD-06CZ'| 'NA'                           | 'IO'       | 'IND SMD 3.3UH20%6A(MMD-06CZ-3R3M-V1W)'         | 'CHIP'         | ''          | ''   | ''          
 '2.2UH'                        | 'SMLF'     | 'IND'    | 'TMP_QCV-2280MZ05'(!)      = ''              | ''                 | 'CV-2280MZ05'              |'L_MMD-06CZ'| '2.2UH'                        | 'DISCRETE' | 'IND SMD 2.2UH 20% 8A MMD-06CZ-2R2M-V1W'        | 'CHIP'         | ''          | ''   | ''          
 '2.2UH'                        | 'SMLF'     | 'EMPTY'  | 'TMP_QCV-2280MZ05'(!)      = ''              | ''                 | 'CV-2280MZ05'              |'L_MMD-06CZ'| 'NA'                           | 'IO'       | 'IND SMD 2.2UH 20% 8A MMD-06CZ-2R2M-V1W'        | 'CHIP'         | ''          | ''   | ''          
 '1UH'                          | 'SMLF'     | 'IND'    | 'TMP_QCV-10M0MZ02'(!)      = ''              | ''                 | 'CV-10M0MZ02'              |'L_MMD-06CZ'| '1UH'                          | 'DISCRETE' | 'IND SMD 1UH +-20%22A(MMD-06CZ-1R0M-V1W)'       | 'CHIP'         | ''          | ''   | ''          
 '1UH'                          | 'SMLF'     | 'EMPTY'  | 'TMP_QCV-10M0MZ02'(!)      = ''              | ''                 | 'CV-10M0MZ02'              |'L_MMD-06CZ'| 'NA'                           | 'IO'       | 'IND SMD 1UH +-20%22A(MMD-06CZ-1R0M-V1W)'       | 'CHIP'         | ''          | ''   | ''          
 'BK2125HS601'                  | 'SMLF'     | 'IND'    | 'CX5HS601007'(!)           = 'End of Design' | 'End of Life'      | 'CX5HS601007'              |'L0805_EOL'| 'BK2125HS601'                  | 'DISCRETE' | 'EMI FILTER CHIP BK2125HS601(200MA,600)'        | 'CHIP'         | ''          | ''   | ''          
 'BK2125HS601'                  | 'SMLF'     | 'EMPTY'  | 'CX5HS601007'(!)           = 'End of Design' | 'End of Life'      | 'CX5HS601007'              |'L0805_EOL'| 'NA'                           | 'IO'       | 'EMI FILTER CHIP BK2125HS601(200MA,600)'        | 'CHIP'         | ''          | ''   | ''          
 'MPZ1608S221AT'                | 'SMLF'     | 'IND'    | 'CX08S221001'(!)           = 'End of Design' | 'End of Life'      | 'CX08S221001'              |'L0603_EOL'| 'MPZ1608S221AT'                | 'DISCRETE' | 'EMI FILTER MPZ1608S221AT(220,2A,0.05)'         | 'CHIP'         | ''          | ''   | ''          
 'MPZ1608S221AT'                | 'SMLF'     | 'EMPTY'  | 'CX08S221001'(!)           = 'End of Design' | 'End of Life'      | 'CX08S221001'              |'L0603_EOL'| 'NA'                           | 'IO'       | 'EMI FILTER MPZ1608S221AT(220,2A,0.05)'         | 'CHIP'         | ''          | ''   | ''          
 '1.5UH'                        | 'SMLF'     | 'IND'    | 'CV-15I0MZ03'(!)           = ''              | ''                 | 'CV-15I0MZ03'              |'L_MMD-06CZ'| '1.5UH'                        | 'DISCRETE' | 'IND SMD 1.5UH 20% 18A(MMD-06CZ-1R5M-V1W)'      | 'CHIP'         | ''          | ''   | ''          
 '1.5UH'                        | 'SMLF'     | 'EMPTY'  | 'CV-15I0MZ03'(!)           = ''              | ''                 | 'CV-15I0MZ03'              |'L_MMD-06CZ'| 'NA'                           | 'IO'       | 'IND SMD 1.5UH 20% 18A(MMD-06CZ-1R5M-V1W)'      | 'CHIP'         | ''          | ''   | ''          
 'HCB1608K-181T15'              | 'SMLF'     | 'IND'    | 'CX000181016'(!)           = 'End of Design' | 'Comp-Approve'     | 'CX000181016'              |'L0603'| 'HCB1608K-181T15'              | 'DISCRETE' | 'EMI FILTER HCB1608KF-181T15(180,1.5A)'         | 'CHIP'         | ''          | ''   | ''          
 'HCB1608K-181T15'              | 'SMLF'     | 'EMPTY'  | 'CX000181016'(!)           = 'End of Design' | 'Comp-Approve'     | 'CX000181016'              |'L0603'| 'NA'                           | 'IO'       | 'EMI FILTER HCB1608KF-181T15(180,1.5A)'         | 'CHIP'         | ''          | ''   | ''          
 '4.7UH'                        | 'SMLF'     | 'IND'    | 'CV-4717MZ00'(!)           = ''              | ''                 | 'CV-4717MZ00'              |'L_MLPS5015'| '4.7UH'                        | 'DISCRETE' | 'IND SMD 4.7UH 20% 1.7A(MLPS-5015-4R7M-E)'      | 'CHIP'         | ''          | ''   | ''          
 '4.7UH'                        | 'SMLF'     | 'EMPTY'  | 'CV-4717MZ00'(!)           = ''              | ''                 | 'CV-4717MZ00'              |'L_MLPS5015'| 'NA'                           | 'IO'       | 'IND SMD 4.7UH 20% 1.7A(MLPS-5015-4R7M-E)'      | 'CHIP'         | ''          | ''   | ''          
 '1.0UH'                        | 'TH'       | 'IND'    | 'CV-10^0MD02'(!)           = ''              | ''                 | 'CV-10^0MD02'              |'L_TFHAH1311'| '1.0UH'                        | 'DISCRETE' | 'IND DIP 1.0UH +-20% 40A(TFHAH1311-1R0G-F'      | 'CHIP'         | ''          | ''   | ''          
 '1.0UH'                        | 'TH'       | 'EMPTY'  | 'CV-10^0MD02'(!)           = ''              | ''                 | 'CV-10^0MD02'              |'L_TFHAH1311'| 'NA'                           | 'IO'       | 'IND DIP 1.0UH +-20% 40A(TFHAH1311-1R0G-F'      | 'CHIP'         | ''          | ''   | ''          
 '1.2UH'                        | 'TH'       | 'IND'    | 'TMP-C_T2B_KC_0702_2'(!)   = ''              | ''                 | 'TMP-C_T2B_KC_0702_2'      |'L_TFHAH1311'| '1.2UH'                        | 'DISCRETE' | 'IND DIP 1.2UH +-20% 40A(TFHAH1311-1R2G-F)'     | 'CHIP'         | ''          | ''   | ''          
 '1.2UH'                        | 'TH'       | 'EMPTY'  | 'TMP-C_T2B_KC_0702_2'(!)   = ''              | ''                 | 'TMP-C_T2B_KC_0702_2'      |'L_TFHAH1311'| 'NA'                           | 'IO'       | 'IND DIP 1.2UH +-20% 40A(TFHAH1311-1R2G-F)'     | 'CHIP'         | ''          | ''   | ''          
 '470NH'                        | 'SMLF'     | 'IND'    | 'CV+47^0MZ02'(!)           = ''              | ''                 | 'CV+47^0MZ02'              |'L_HCB1190B'| '470NH'                        | 'DISCRETE' | 'IND SMD 470NH,+-20%,42A(HCB1190-471L)'         | 'CHIP'         | ''          | ''   | ''          
 '470NH'                        | 'SMLF'     | 'EMPTY'  | 'CV+47^0MZ02'(!)           = ''              | ''                 | 'CV+47^0MZ02'              |'L_HCB1190B'| 'NA'                           | 'IO'       | 'IND SMD 470NH,+-20%,42A(HCB1190-471L)'         | 'CHIP'         | ''          | ''   | ''          
 'TI321611U600'                 | 'SMLF'     | 'IND'    | 'CX11U600000'(!)           = 'End of Design' | 'End of Life'      | 'CX11U600000'              |'L1206_EOL'| 'TI321611U600'                 | 'DISCRETE' | 'EMI FILTER TI321611U600(60,3000MA)'            | 'CHIP'         | ''          | ''   | ''          
 'TI321611U600'                 | 'SMLF'     | 'EMPTY'  | 'CX11U600000'(!)           = 'End of Design' | 'End of Life'      | 'CX11U600000'              |'L1206_EOL'| 'NA'                           | 'IO'       | 'EMI FILTER TI321611U600(60,3000MA)'            | 'CHIP'         | ''          | ''   | ''          
 'MMZ1608S601A'                 | 'SMLF'     | 'IND'    | 'CX0S601A009'(!)           = 'End of Design' | 'Comp-Approve'     | 'CX0S601A009'              |'L0603'| 'MMZ1608S601A'                 | 'DISCRETE' | 'EMI FILTER MMZ1608S601A(400,100MHZ)EP'         | 'CHIP'         | ''          | ''   | ''          
 'MMZ1608S601A'                 | 'SMLF'     | 'EMPTY'  | 'CX0S601A009'(!)           = 'End of Design' | 'Comp-Approve'     | 'CX0S601A009'              |'L0603'| 'NA'                           | 'IO'       | 'EMI FILTER MMZ1608S601A(400,100MHZ)EP'         | 'CHIP'         | ''          | ''   | ''          
 'BLM18PG300SN1D'               | 'SMLF'     | 'IND'    | 'CX11P300000'(!)           = ''              | 'End of Life'      | 'CX11P300000'              |'L0603_EOL'| 'BLM18PG300SN1D'               | 'DISCRETE' | 'EMI FILTER CHIP BLM18PG300SN1D(1000MA)'        | 'CHIP'         | ''          | ''   | ''          
 'BLM18PG300SN1D'               | 'SMLF'     | 'EMPTY'  | 'CX11P300000'(!)           = ''              | 'End of Life'      | 'CX11P300000'              |'L0603_EOL'| 'NA'                           | 'IO'       | 'EMI FILTER CHIP BLM18PG300SN1D(1000MA)'        | 'CHIP'         | ''          | ''   | ''          
 '4.7UH'                        | 'SMLF'     | 'IND'    | 'CV-4701MN00'(!)           = 'End of Design' | 'Comp-Approve'     | 'CV-4701MN00'              |'L_MLZ2012'| '4.7UH      '                  | 'DISCRETE' | 'IND CHIP 4.7U,20%,80MA(MLZ2012E4R7MT)   '      | 'CHIP'         | ''          | ''   | '20100718'  
 '4.7UH'                        | 'SMLF'     | 'EMPTY'  | 'CV-4701MN00'(!)           = 'End of Design' | 'Comp-Approve'     | 'CV-4701MN00'              |'L_MLZ2012'| 'NA'                           | 'IO'       | 'IND CHIP 4.7U,20%,80MA(MLZ2012E4R7MT)   '      | 'CHIP'         | ''          | ''   | '20100718'  
 '4.7UH'                        | 'SMLF'     | 'IND'    | 'CV-4701TN01'(!)           = 'End of Design' | 'Comp-Approve'     | 'CV-4701TN01'              |'L0805'| '4.7UH      '                  | 'DISCRETE' | 'IND CHIP 4.7UH +-25%,80MA(MLZ2012E4R7PT)'      | 'CHIP'         | ''          | ''   | '20100718'  
 '4.7UH'                        | 'SMLF'     | 'EMPTY'  | 'CV-4701TN01'(!)           = 'End of Design' | 'Comp-Approve'     | 'CV-4701TN01'              |'L0805'| 'NA'                           | 'IO'       | 'IND CHIP 4.7UH +-25%,80MA(MLZ2012E4R7PT)'      | 'CHIP'         | ''          | ''   | '20100718'  
 'BLM18BB121S'                  | 'SMLF'     | 'IND'    | 'CX8BB121002'(!)           = ''              | ''                 | 'CX8BB121002'              |'L0603'| 'BLM18BB121S'                  | 'DISCRETE' | 'EMI FILTER BLM18BB121SN1D(120 0.2A)     '      | 'CHIP'         | ''          | ''   | '20100718'  
 'BLM18BB121S'                  | 'SMLF'     | 'EMPTY'  | 'CX8BB121002'(!)           = ''              | ''                 | 'CX8BB121002'              |'L0603'| 'NA'                           | 'IO'       | 'EMI FILTER BLM18BB121SN1D(120 0.2A)     '      | 'CHIP'         | ''          | ''   | '20100718'  
 '0.2UH'                        | 'SMLF'     | 'IND'    | 'CV+20^0MZ02'(!)           = 'End of Design' | 'End of Life'      | 'CV+20^0MZ02'              |'L_SFI060675R20MHF_EOL'| '0.2UH'                        | 'DISCRETE' | 'IND SMD 0.2UH,+-20%,35A(SFI060675-R20M)     '  | 'CHIP'         | ''          | ''   | '20100722'  
 '0.2UH'                        | 'SMLF'     | 'EMPTY'  | 'CV+20^0MZ02'(!)           = 'End of Design' | 'End of Life'      | 'CV+20^0MZ02'              |'L_SFI060675R20MHF_EOL'| 'NA'                           | 'IO'       | 'IND SMD 0.2UH,+-20%,35A(SFI060675-R20M)    '   | 'CHIP'         | ''          | ''   | '20100722'  
 '1.2UH'                        | 'THLF'     | 'IND'    | 'DC-12W0M000'(!)           = ''              | ''                 | 'DC-12W0M000'              |'LC_APL1310P1R2M'| '1.2UH'                        | 'DISCRETE' | 'CHOCK COIL(1.2UH+-20%31A)APL1310PQ-1R2M     '  | 'CHIP'         | ''          | ''   | '20100915'  
 '1.2UH'                        | 'THLF'     | 'EMPTY'  | 'DC-12W0M000'(!)           = ''              | ''                 | 'DC-12W0M000'              |'LC_APL1310P1R2M'| 'NA'                           | 'IO'       | 'CHOCK COIL(1.2UH+-20%31A)APL1310PQ-1R2M     '  | 'CHIP'         | ''          | ''   | '2010915'   
 '33NH'                         | 'SMLF'     | 'IND'    | 'CV+03G04N00'(!)           = ''              | 'End of Life'      | 'CV+03G04N00'              |'L0402XA_EOL'| '33NH'                         | 'DISCRETE' | 'IND CHIP 33NH,2%,400MA(HFC-1005C-33NG)    '    | 'CHIP'         | ''          | ''   | '20100805'  
 '33NH'                         | 'SMLF'     | 'EMPTY'  | 'CV+03G04N00'(!)           = ''              | 'End of Life'      | 'CV+03G04N00'              |'L0402XA_EOL'| 'NA'                           | 'IO'       | 'IND CHIP 33NH,2%,400MA(HFC-1005C-33NG)    '    | 'CHIP'         | ''          | ''   | '20100805'  
 'GB160808D500TT'               | 'SMLF'     | 'IND'    | 'CX08D500002'(!)           = 'End of Design' | 'Comp-Approve'     | 'CX08D500002'              |'L0603'| 'GB160808D500TT'               | 'DISCRETE' | 'EMI FILTER GB160808D500TT(50,600MA)    '       | 'CHIP'         | ''          | ''   | '20100814'  
 'GB160808D500TT'               | 'SMLF'     | 'EMPTY'  | 'CX08D500002'(!)           = 'End of Design' | 'Comp-Approve'     | 'CX08D500002'              |'L0603'| 'NA'                           | 'IO'       | 'EMI FILTER GB160808D500TT(50,600MA)    '       | 'CHIP'         | ''          | ''   | '20100814'  
 '300NH'                        | 'SMLF'     | 'IND'    | 'CV+30^0KZ01'(!)           = ''              | ''                 | 'CV+30^0KZ01'              |'L_HCB1290'| '300NH'                        | 'DISCRETE' | 'IND SMD 300NH +-10% 62A(HCB1290-301)    '      | 'CHIP'         | ''          | ''   | '20100816'  
 '300NH'                        | 'SMLF'     | 'EMPTY'  | 'CV+30^0KZ01'(!)           = ''              | ''                 | 'CV+30^0KZ01'              |'L_HCB1290'| 'NA'                           | 'IO'       | 'IND SMD 300NH +-10% 62A(HCB1290-301)    '      | 'CHIP'         | ''          | ''   | '20100816'  
 '1.5UH'                        | 'SMLF'     | 'IND'    | 'CV-1507MN00'(!)           = ''              | ''                 | 'CV-1507MN00'              |'L0805'| '1.5UH      '                  | 'DISCRETE' | 'IND CHIP 1.5UH 20%,0.7A(LQM21PN1R5MC0D)'       | 'CHIP'         | ''          | ''   | '20100908'  
 '1.5UH'                        | 'SMLF'     | 'EMPTY'  | 'CV-1507MN00'(!)           = ''              | ''                 | 'CV-1507MN00'              |'L0805'| 'NA'                           | 'IO'       | 'IND CHIP 1.5UH 20%,0.7A(LQM21PN1R5MC0D)'       | 'CHIP'         | ''          | ''   | '20100908'  
 'MPZ1608S601AT'                | 'SMLF'     | 'IND'    | 'CX08S601008'(!)           = 'End of Design' | 'Comp-Approve'     | 'CX08S601008'              |'L0603'| 'MPZ1608S601AT '               | 'DISCRETE' | 'EMI FILTER MPZ1608S601AT(600,1A,0.15)    '     | 'CHIP'         | ''          | ''   | '20100909'  
 'MPZ1608S601AT'                | 'SMLF'     | 'EMPTY'  | 'CX08S601008'(!)           = 'End of Design' | 'Comp-Approve'     | 'CX08S601008'              |'L0603'| 'NA'                           | 'IO'       | 'EMI FILTER MPZ1608S601AT(600,1A,0.15)    '     | 'CHIP'         | ''          | ''   | '20100909'  
 '0.6UH'                        | 'SMLF'     | 'IND'    | 'DC+60^0M000'(!)           = ''              | ''                 | 'DC+60^0M000'              |'LC_APL1108P'| '0.6UH'                        | 'DISCRETE' | 'CHOKE DIP 0.6UH +-20% 38A APL1108P-R60M    '   | 'CHIP'         | ''          | ''   | '20100819'  
 '0.6UH'                        | 'SMLF'     | 'EMPTY'  | 'DC+60^0M000'(!)           = ''              | ''                 | 'DC+60^0M000'              |'LC_APL1108P'| 'NA'                           | 'IO'       | 'CHOKE DIP 0.6UH +-20% 38A APL1108P-R60M    '   | 'CHIP'         | ''          | ''   | '20100819'  
 '1UH'                          | 'SMLF'     | 'IND'    | 'DC-10D0M002'(!)           = ''              | ''                 | 'DC-10D0M002'              |'LC_APL0806PC'| '1UH'                          | 'DISCRETE' | 'CHOKE 1UH+-20% 13A_APL0806PC-1R0M-C    '       | 'CHIP'         | ''          | ''   | '20100819'  
 '1UH'                          | 'SMLF'     | 'EMPTY'  | 'DC-10D0M002'(!)           = ''              | ''                 | 'DC-10D0M002'              |'LC_APL0806PC'| 'NA'                           | 'IO'       | 'CHOKE 1UH+-20% 13A_APL0806PC-1R0M-C    '       | 'CHIP'         | ''          | ''   | '20100819'  
 '1.2UH'                        | 'SMLF'     | 'IND'    | 'DC-12I0L002'(!)           = ''              | ''                 | 'DC-12I0L002'              |'LC_APL11T08PM'| '1.2UH'                        | 'DISCRETE' | 'CHOCK COIL 1.2UH +-15% 18A APL11T08PM    '     | 'CHIP'         | ''          | ''   | '20100819'  
 '1.2UH'                        | 'SMLF'     | 'EMPTY'  | 'DC-12I0L002'(!)           = ''              | ''                 | 'DC-12I0L002'              |'LC_APL11T08PM'| 'NA'                           | 'IO'       | 'CHOCK COIL 1.2UH +-15% 18A APL11T08PM    '     | 'CHIP'         | ''          | ''   | '20100819'  
 '3.3UH'                        | 'SMLF'     | 'IND'    | 'DC-33H0M000'(!)           = ''              | ''                 | 'DC-33H0M000'              |'LC_APL1109M'| '3.3UH'                        | 'DISCRETE' | 'CHOCK COIL 3.3UH +-20% 17A APL1109M-3R3M    '  | 'CHIP'         | ''          | ''   | '20100819'  
 '3.3UH'                        | 'SMLF'     | 'EMPTY'  | 'DC-33H0M000'(!)           = ''              | ''                 | 'DC-33H0M000'              |'LC_APL1109M'| 'NA'                           | 'IO'       | 'CHOCK COIL 3.3UH +-20% 17A APL1109M-3R3M    '  | 'CHIP'         | ''          | ''   | '20100819'  
 '5UH'                          | 'SMLF'     | 'IND'    | 'DC-50A0M002'(!)           = ''              | ''                 | 'DC-50A0M002'              |'LC_APL1108P6CQ'| '5UH'                          | 'DISCRETE' | 'CHOKE 5UH+-20% 10A_APL1108P6CQ-5R0M-C    '     | 'CHIP'         | ''          | ''   | '20100819'  
 '5UH'                          | 'SMLF'     | 'EMPTY'  | 'DC-50A0M002'(!)           = ''              | ''                 | 'DC-50A0M002'              |'LC_APL1108P6CQ'| 'NA'                           | 'IO'       | 'CHOKE 5UH+-20% 10A_APL1108P6CQ-5R0M-C    '     | 'CHIP'         | ''          | ''   | '20100819'  
 '4.7UH'                        | 'SMLF'     | 'IND'    | 'DC-47A0M001'(!)           = ''              | ''                 | 'DC-47A0M001'              |'LC_APL1108P-4R7M'| '4.7UH'                        | 'DISCRETE' | 'CHOCK COIL 4.7UH +-20% 10A APL1108P-4R7M    '  | 'CHIP'         | ''          | ''   | '20100920'  
 '4.7UH'                        | 'SMLF'     | 'EMPTY'  | 'DC-47A0M001'(!)           = ''              | ''                 | 'DC-47A0M001'              |'LC_APL1108P-4R7M'| 'NA'                           | 'IO'       | 'CHOCK COIL 4.7UH +-20% 10A APL1108P-4R7M    '  | 'CHIP'         | ''          | ''   | '20100920'  
 '3.3UH'                        | 'SMLF'     | 'IND'    | 'DC-33E0M000'(!)           = ''              | ''                 | 'DC-33E0M000'              |'LC_APL1108P-3R3M'| '3.3UH'                        | 'DISCRETE' | 'CHOCK COIL 3.3UH +-20% 14A APL1108P-3R3M    '  | 'CHIP'         | ''          | ''   | '20100920'  
 '3.3UH'                        | 'SMLF'     | 'EMPTY'  | 'DC-33E0M000'(!)           = ''              | ''                 | 'DC-33E0M000'              |'LC_APL1108P-3R3M'| 'NA'                           | 'IO'       | 'CHOCK COIL 3.3UH +-20% 14A APL1108P-3R3M    '  | 'CHIP'         | ''          | ''   | '20100920'  
 '4.7UH'                        | 'SMLF'     | 'IND'    | 'CV-47A0MZ10'(!)           = ''              | ''                 | 'CV-47A0MZ10'              |'L_PCMB104EXB'| '4.7UH'                        | 'DISCRETE' | 'IND SMD 4.7UH +-20% 10A(PCMB104E-4R7MS)'       | 'CHIP'         | ''          | ''   | '20110221'  
 '4.7UH'                        | 'SMLF'     | 'EMPTY'  | 'CV-47A0MZ10'(!)           = ''              | ''                 | 'CV-47A0MZ10'              |'L_PCMB104EXB'| 'NA'                           | 'IO'       | 'IND SMD 4.7UH +-20% 10A(PCMB104E-4R7MS)'       | 'CHIP'         | ''          | ''   | '20110221'  
 'BLM18EG221TN1D'               | 'SMLF'     | 'IND'    | 'CX8EG221003'(!)           = 'End of Design' | 'Comp-Approve'     | 'CX8EG221003'              |'L0603'| 'BLM18EG221TN1D '              | 'DISCRETE' | 'EMI FILTER BLM18EG221TN1D(220,1000MA)    '     | 'CHIP'         | ''          | ''   | '20100924'  
 'BLM18EG221TN1D'               | 'SMLF'     | 'EMPTY'  | 'CX8EG221003'(!)           = 'End of Design' | 'Comp-Approve'     | 'CX8EG221003'              |'L0603'| 'NA'                           | 'IO'       | 'EMI FILTER BLM18EG221TN1D(220,1000MA)    '     | 'CHIP'         | ''          | ''   | '20100924'  
 '1.5UH'                        | 'SMLF'     | 'IND'    | 'DC-15Q0M000'(!)           = ''              | ''                 | 'DC-15Q0M000'              |'LC_APL1108P-1R5M'| '1.5UH'                        | 'DISCRETE' | 'CHOCK COIL 1.5UH+-20%35A(APL1108P-1R5M)    '   | 'CHIP'         | ''          | ''   | '20100924'  
 '1.5UH'                        | 'SMLF'     | 'EMPTY'  | 'DC-15Q0M000'(!)           = ''              | ''                 | 'DC-15Q0M000'              |'LC_APL1108P-1R5M'| 'NA'                           | 'IO'       | 'CHOCK COIL 1.5UH+-20%35A(APL1108P-1R5M)    '   | 'CHIP'         | ''          | ''   | '20100924'  
 '2UH'                          | 'SMLF'     | 'IND'    | 'DC-20V0M000'(!)           = ''              | ''                 | 'DC-20V0M000'              |'LC_APL1108P-2R0M'| '2UH'                          | 'DISCRETE' | 'CHOCK COIL 2UH+-20% 35A(APL1108P-2R0M)     '   | 'CHIP'         | ''          | ''   | '20100924'  
 '2UH'                          | 'SMLF'     | 'EMPTY'  | 'DC-20V0M000'(!)           = ''              | ''                 | 'DC-20V0M000'              |'LC_APL1108P-2R0M'| 'NA'                           | 'IO'       | 'CHOCK COIL 2UH+-20% 35A(APL1108P-2R0M)     '   | 'CHIP'         | ''          | ''   | '20100924'  
 '0.68UH'                       | 'SMLF'     | 'IND'    | 'CV+68F5MZ03'(!)           = ''              | ''                 | 'CV+68F5MZ03'              |'L_MMD-06CZ'| '0.68UH'                       | 'DISCRETE' | 'IND SMD 0.68UH20%15.5A,MMD-06CZ-R68M-V1Q'      | 'CHIP'         | ''          | ''   | '20101004'  
 '0.68UH'                       | 'SMLF'     | 'EMPTY'  | 'CV+68F5MZ03'(!)           = ''              | ''                 | 'CV+68F5MZ03'              |'L_MMD-06CZ'| 'NA'                           | 'IO'       | 'IND SMD 0.68UH20%15.5A,MMD-06CZ-R68M-V1Q'      | 'CHIP'         | ''          | ''   | '20101004'  
 '4.7UH'                        | 'SMLF'     | 'IND'    | 'CV-4705MN06'(!)           = 'End of Design' | 'End of Life'      | 'CV-4705MN06'              |'L0805_H56_EOL'| '4.7UH'                        | 'DISCRETE' | 'IND CHIP 4.7UH+-20%450MA(GLF2012T4R7M)EP'      | 'CHIP'         | ''          | ''   | '20101005'  
 '4.7UH'                        | 'SMLF'     | 'EMPTY'  | 'CV-4705MN06'(!)           = 'End of Design' | 'End of Life'      | 'CV-4705MN06'              |'L0805_H56_EOL'| 'NA'                           | 'IO'       | 'IND CHIP 4.7UH+-20%450MA(GLF2012T4R7M)EP'      | 'CHIP'         | ''          | ''   | '20101005'  
 'TI160808U601'                 | 'SMLF'     | 'IND'    | 'CX08U601017'(!)           = 'End of Design' | 'End of Life'      | 'CX08U601017'              |'L0603_EOL'| 'TI160808U601'                 | 'DISCRETE' | 'EMI FILTER CHIP TI160808U601(600,200MA)'       | 'CHIP'         | ''          | ''   | '20101005'  
 'TI160808U601'                 | 'SMLF'     | 'EMPTY'  | 'CX08U601017'(!)           = 'End of Design' | 'End of Life'      | 'CX08U601017'              |'L0603_EOL'| 'NA'                           | 'IO'       | 'EMI FILTER CHIP TI160808U601(600,200MA)'       | 'CHIP'         | ''          | ''   | '20101005'  
 'MPZ2012S300A'                 | 'SMLF'     | 'IND'    | 'CX12S300003'(!)           = 'End of Design' | 'End of Life'      | 'CX12S300003'              |'L0805_EOL'| 'MPZ2012S300A'                 | 'DISCRETE' | 'EMI FIL CHIP MPZ2012S300AT (30 OHM,5A)EU'      | 'CHIP'         | ''          | ''   | '20101005'  
 'MPZ2012S300A'                 | 'SMLF'     | 'EMPTY'  | 'CX12S300003'(!)           = 'End of Design' | 'End of Life'      | 'CX12S300003'              |'L0805_EOL'| 'NA'                           | 'IO'       | 'EMI FIL CHIP MPZ2012S300AT (30 OHM,5A)EU'      | 'CHIP'         | ''          | ''   | '20101005'  
 'BLM41PG600SN1L'               | 'SMLF'     | 'IND'    | 'CX41PG60006'(!)           = ''              | ''                 | 'CX41PG60006'              |'L1806'| 'BLM41PG600SN1L'               | 'DISCRETE' | 'EMI FILTER CHIP BLM41PG600SN1L(60,6A)'         | 'CHIP'         | ''          | ''   | '20101005'  
 'BLM41PG600SN1L'               | 'SMLF'     | 'EMPTY'  | 'CX41PG60006'(!)           = ''              | ''                 | 'CX41PG60006'              |'L1806'| 'NA'                           | 'IO'       | 'EMI FILTER CHIP BLM41PG600SN1L(60,6A)'         | 'CHIP'         | ''          | ''   | '20101005'  
 '1.0UH'                        | 'THLF'     | 'IND'    | 'CV-10K0KD07'(!)           = 'End of Design' | 'End of Life'      | 'CV-10K0KD07'              |'LC14_P7-62_EOL'| '1.0UH'                        | 'DISCRETE' | 'INDUCTOR 1.0UH(+-10%,20A,HM00-01800LF)'        | 'CHIP'         | ''          | ''   | '20101008'  
 '1.0UH'                        | 'THLF'     | 'EMPTY'  | 'CV-10K0KD07'(!)           = 'End of Design' | 'End of Life'      | 'CV-10K0KD07'              |'LC14_P7-62_EOL'| 'NA'                           | 'IO'       | 'INDUCTOR 1.0UH(+-10%,20A,HM00-01800LF)'        | 'CHIP'         | ''          | ''   | '20101008'  
 '1.0UH'                        | 'THLF_SEL' | 'IND'    | 'CV-10K0KD07'(!)           = 'End of Design' | 'End of Life'      | 'CV-10K0KD07'              |'G_LC14_P7-62_EOL'| '1.0UH'                        | 'DISCRETE' | 'INDUCTOR 1.0UH(+-10%,20A,HM00-01800LF)'        | 'CHIP'         | ''          | ''   | '20101008'  
 '1.0UH'                        | 'THLF_SEL' | 'EMPTY'  | 'CV-10K0KD07'(!)           = 'End of Design' | 'End of Life'      | 'CV-10K0KD07'              |'G_LC14_P7-62_EOL'| 'NA'                           | 'IO'       | 'INDUCTOR 1.0UH(+-10%,20A,HM00-01800LF)'        | 'CHIP'         | ''          | ''   | '20101008'  
 '0.82UH'                       | 'SMLF'     | 'IND'    | 'CV+82W0MZ00'(!)           = ''              | ''                 | 'CV+82W0MZ00'              |'L_MMD12EZ'| '0.82UH'                       | 'DISCRETE' | 'IND SMD 0.82UH +-20%31A(MMD-12EZ-R82M)'        | 'CHIP'         | ''          | ''   | '20101025'  
 '0.82UH'                       | 'SMLF'     | 'EMPTY'  | 'CV+82W0MZ00'(!)           = ''              | ''                 | 'CV+82W0MZ00'              |'L_MMD12EZ'| 'NA'                           | 'IO'       | 'IND SMD 0.82UH +-20%31A(MMD-12EZ-R82M)'        | 'CHIP'         | ''          | ''   | '20101025'  
 '0.38UH'                       | 'SMLF'     | 'IND'    | 'CV+38^0EZ00'(!)           = ''              | ''                 | 'CV+38^0EZ00'              |'L_SIHH111109'| '0.38UH'                       | 'DISCRETE' | 'IND SMD 0.38U+-15% 42A(SIHH111109-R38L)'       | 'CHIP'         | ''          | ''   | '20101009'  
 '0.38UH'                       | 'SMLF'     | 'EMPTY'  | 'CV+38^0EZ00'(!)           = ''              | ''                 | 'CV+38^0EZ00'              |'L_SIHH111109'| 'NA'                           | 'IO'       | 'IND SMD 0.38U+-15% 42A(SIHH111109-R38L)'       | 'CHIP'         | ''          | ''   | '20101009'  
 '0.23UH'                       | 'SMLF'     | 'IND'    | 'CV+23^0MZ04'(!)           = ''              | ''                 | 'CV+23^0MZ04'              |'L_SIHH1309XA'| '0.23UH'                       | 'DISCRETE' | 'IND SMD 0.23U 20% 45A(SIHH1309-R23M-R30)'      | 'CHIP'         | ''          | ''   | '20101118'  
 '0.23UH'                       | 'SMLF'     | 'EMPTY'  | 'CV+23^0MZ04'(!)           = ''              | ''                 | 'CV+23^0MZ04'              |'L_SIHH1309XA'| 'NA'                           | 'IO'       | 'IND SMD 0.23U 20% 45A(SIHH1309-R23M-R30)'      | 'CHIP'         | ''          | ''   | '20101118'  
 '2.2UH'                        | 'SMLF'     | 'IND'    | 'CV-22X0MZ00'(!)           = ''              | ''                 | 'CV-22X0MZ00'              |'L_PCMC135T'| '2.2UH'                        | 'DISCRETE' | 'IND SMD 2.2UH 20% 32A(PCMC135T-2R2MF)'         | 'CHIP'         | ''          | ''   | '20110105'  
 '2.2UH'                        | 'SMLF'     | 'EMPTY'  | 'CV-22X0MZ00'(!)           = ''              | ''                 | 'CV-22X0MZ00'              |'L_PCMC135T'| 'NA'                           | 'IO'       | 'IND SMD 2.2UH 20% 32A(PCMC135T-2R2MF)'         | 'CHIP'         | ''          | ''   | '20110105'  
 '3.3UH'                        | 'SMLF'     | 'IND'    | 'CV-33X0MZ00'(!)           = ''              | ''                 | 'CV-33X0MZ00'              |'L_PCMC135T'| '3.3UH'                        | 'DISCRETE' | 'IND SMD 3.3UH 20% 32A(PCMC135T-3R3MF)'         | 'CHIP'         | ''          | ''   | '20110105'  
 '3.3UH'                        | 'SMLF'     | 'EMPTY'  | 'CV-33X0MZ00'(!)           = ''              | ''                 | 'CV-33X0MZ00'              |'L_PCMC135T'| 'NA'                           | 'IO'       | 'IND SMD 3.3UH 20% 32A(PCMC135T-3R3MF)'         | 'CHIP'         | ''          | ''   | '20110105'  
 'BLM21PG331SN1D'               | 'SMLF'     | 'IND'    | 'CX1PG331001'(!)           = 'End of Design' | 'Comp-Approve'     | 'CX1PG331001'              |'L0805'| 'BLM21PG331SN1D'               | 'DISCRETE' | 'EMI FIL CHIP BLM21PG331SN1D(330,1.5A)'         | 'CHIP'         | ''          | ''   | '20110114'  
 'BLM21PG331SN1D'               | 'SMLF'     | 'EMPTY'  | 'CX1PG331001'(!)           = 'End of Design' | 'Comp-Approve'     | 'CX1PG331001'              |'L0805'| 'NA'                           | 'IO'       | 'EMI FIL CHIP BLM21PG331SN1D(330,1.5A)'         | 'CHIP'         | ''          | ''   | '20110114'  
 '0.22U'                        | 'SMLF'     | 'IND'    | 'CV+22^0KZ02'(!)           = ''              | ''                 | 'CV+22^0KZ02'              |'L_SI2C100709'| '0.22U'                        | 'DISCRETE' | 'IND SMD 0.22U +-10% 45A(SI2C100709-R22K)'      | 'CHIP'         | ''          | ''   | '20110307'  
 '0.22U'                        | 'SMLF'     | 'EMPTY'  | 'CV+22^0KZ02'(!)           = ''              | ''                 | 'CV+22^0KZ02'              |'L_SI2C100709'| 'NA'                           | 'IO'       | 'IND SMD 0.22U +-10% 45A(SI2C100709-R22K)'      | 'CHIP'         | ''          | ''   | '20110307'  
 '0.27U'                        | 'SMLF'     | 'IND'    | 'CV+27^0KZ00'(!)           = ''              | ''                 | 'CV+27^0KZ00'              |'L_SI2C100709'| '0.27U'                        | 'DISCRETE' | 'IND SMD 0.27U +-10% 45A(SI2C100709-R27K)'      | 'CHIP'         | ''          | ''   | '20110307'  
 '0.27U'                        | 'SMLF'     | 'EMPTY'  | 'CV+27^0KZ00'(!)           = ''              | ''                 | 'CV+27^0KZ00'              |'L_SI2C100709'| 'NA'                           | 'IO'       | 'IND SMD 0.27U +-10% 45A(SI2C100709-R27K)'      | 'CHIP'         | ''          | ''   | '20110307'  
 '2.2UH'                        | 'SMLF'     | 'IND'    | 'CV-22X0MZ01'(!)           = ''              | ''                 | 'CV-22X0MZ01'              |'L_MMD12EZXA'| '2.2UH'                        | 'DISCRETE' | 'IND SMD 2.2UH 20% 32A(MMD-12EZ-2R2M-V1Q)'      | 'CHIP'         | ''          | ''   | '20110131'  
 '2.2UH'                        | 'SMLF'     | 'EMPTY'  | 'CV-22X0MZ01'(!)           = ''              | ''                 | 'CV-22X0MZ01'              |'L_MMD12EZXA'| 'NA'                           | 'IO'       | 'IND SMD 2.2UH 20% 32A(MMD-12EZ-2R2M-V1Q)'      | 'CHIP'         | ''          | ''   | '20110131'  
 '3.3UH'                        | 'SMLF'     | 'IND'    | 'CV-33X0MZ01'(!)           = ''              | ''                 | 'CV-33X0MZ01'              |'L_MMD12EZXA'| '3.3UH'                        | 'DISCRETE' | 'IND SMD 3.3UH 20% 32A(MMD-12EZ-3R3M-V1Q)'      | 'CHIP'         | ''          | ''   | '20110131'  
 '3.3UH'                        | 'SMLF'     | 'EMPTY'  | 'CV-33X0MZ01'(!)           = ''              | ''                 | 'CV-33X0MZ01'              |'L_MMD12EZXA'| 'NA'                           | 'IO'       | 'IND SMD 3.3UH 20% 32A(MMD-12EZ-3R3M-V1Q)'      | 'CHIP'         | ''          | ''   | '20110131'  
 '4.7UH'                        | 'SMLF'     | 'IND'    | 'CV-47S0MZ00'(!)           = ''              | ''                 | 'CV-47S0MZ00'              |'L_MMD12EZXA'| '4.7UH'                        | 'DISCRETE' | 'IND SMD 4.7UH 20% 27A(MMD-12EZ-4R7M-V1Q)'      | 'CHIP'         | ''          | ''   | '20110131'  
 '4.7UH'                        | 'SMLF'     | 'EMPTY'  | 'CV-47S0MZ00'(!)           = ''              | ''                 | 'CV-47S0MZ00'              |'L_MMD12EZXA'| 'NA'                           | 'IO'       | 'IND SMD 4.7UH 20% 27A(MMD-12EZ-4R7M-V1Q)'      | 'CHIP'         | ''          | ''   | '20110131'  
 '47NH'                         | 'SMLF'     | 'IND'    | 'CVA4703MZ00'(!)           = 'End of Design' | 'Comp-Approve'     | 'CVA4703MZ00'              |'L0805'| '47NH'                         | 'DISCRETE' | 'IND SMD 47N +-20% 300MA(MLF2012D47NMT)'        | 'CHIP'         | ''          | ''   | '20110208'  
 '47NH'                         | 'SMLF'     | 'EMPTY'  | 'CVA4703MZ00'(!)           = 'End of Design' | 'Comp-Approve'     | 'CVA4703MZ00'              |'L0805'| 'NA'                           | 'IO'       | 'IND SMD 47N +-20% 300MA(MLF2012D47NMT)'        | 'CHIP'         | ''          | ''   | '20110208'  
 '4.7UH'                        | 'SMLF'     | 'IND'    | 'CV-4702MN00'(!)           = ''              | ''                 | 'CV-4702MN00'              |'L0805'| '4.7UH'                        | 'DISCRETE' | 'IND CHIP 4.7UH+-20% 140MA(LB2012T4R7M)LF'      | 'CHIP'         | ''          | ''   | '20110219'  
 '4.7UH'                        | 'SMLF'     | 'EMPTY'  | 'CV-4702MN00'(!)           = ''              | ''                 | 'CV-4702MN00'              |'L0805'| 'NA'                           | 'IO'       | 'IND CHIP 4.7UH+-20% 140MA(LB2012T4R7M)LF'      | 'CHIP'         | ''          | ''   | '20110219'  
 '0.22UH'                       | 'SMLF'     | 'IND'    | 'CV+2290MZ00'(!)           = ''              | ''                 | 'CV+2290MZ00'              |'L_PCMB042T'| '0.22UH'                       | 'DISCRETE' | 'IND SMD 0.22UH +-20% 9A(PCMB042T-R22MS)'       | 'CHIP'         | ''          | ''   | '20110216'  
 '0.22UH'                       | 'SMLF'     | 'EMPTY'  | 'CV+2290MZ00'(!)           = ''              | ''                 | 'CV+2290MZ00'              |'L_PCMB042T'| 'NA'                           | 'IO'       | 'IND SMD 0.22UH +-20% 9A(PCMB042T-R22MS)'       | 'CHIP'         | ''          | ''   | '20110216'  
 '0.10UH'                       | 'SMLF'     | 'IND'    | 'CV+10X5MZ03'(!)           = ''              | ''                 | 'CV+10X5MZ03'              |'L_PCMC063T'| '0.10UH'                       | 'DISCRETE' | 'IND 0.10UH 32.5A,+-20%(PCMC063T-R10MN)'        | 'CHIP'         | ''          | ''   | '20110221'  
 '0.10UH'                       | 'SMLF'     | 'EMPTY'  | 'CV+10X5MZ03'(!)           = ''              | ''                 | 'CV+10X5MZ03'              |'L_PCMC063T'| 'NA'                           | 'IO'       | 'IND 0.10UH 32.5A,+-20%(PCMC063T-R10MN)'        | 'CHIP'         | ''          | ''   | '20110221'  
 '0.22UH'                       | 'SMLF'     | 'IND'    | 'CV+22N0MZ04'(!)           = ''              | ''                 | 'CV+22N0MZ04'              |'L_PCMC063T'| '0.22UH'                       | 'DISCRETE' | 'IND SMD 0.22UH 23A20%(PCMC063T-R22MN)'         | 'CHIP'         | ''          | ''   | '20110221'  
 '0.22UH'                       | 'SMLF'     | 'EMPTY'  | 'CV+22N0MZ04'(!)           = ''              | ''                 | 'CV+22N0MZ04'              |'L_PCMC063T'| 'NA'                           | 'IO'       | 'IND SMD 0.22UH 23A20%(PCMC063T-R22MN)'         | 'CHIP'         | ''          | ''   | '20110221'  
 '0.33UH'                       | 'SMLF'     | 'IND'    | 'CV+33K0MZ03'(!)           = ''              | ''                 | 'CV+33K0MZ03'              |'L_PCMC063T'| '0.33UH'                       | 'DISCRETE' | 'IND 0.33UH(20A +-20%,PCMC063T-R33MN)'          | 'CHIP'         | ''          | ''   | '20110221'  
 '0.33UH'                       | 'SMLF'     | 'EMPTY'  | 'CV+33K0MZ03'(!)           = ''              | ''                 | 'CV+33K0MZ03'              |'L_PCMC063T'| 'NA'                           | 'IO'       | 'IND 0.33UH(20A +-20%,PCMC063T-R33MN)'          | 'CHIP'         | ''          | ''   | '20110221'  
 '0.47UH'                       | 'SMLF'     | 'IND'    | 'CV+47R0MZ07'(!)           = ''              | ''                 | 'CV+47R0MZ07'              |'L_PCMC063T'| '0.47UH'                       | 'DISCRETE' | 'IND SMD 0.47UH 20% 26A(PCMC063T-R47MN)'        | 'CHIP'         | ''          | ''   | '20110221'  
 '0.47UH'                       | 'SMLF'     | 'EMPTY'  | 'CV+47R0MZ07'(!)           = ''              | ''                 | 'CV+47R0MZ07'              |'L_PCMC063T'| 'NA'                           | 'IO'       | 'IND SMD 0.47UH 20% 26A(PCMC063T-R47MN)'        | 'CHIP'         | ''          | ''   | '20110221'  
 '0.68UH'                       | 'SMLF'     | 'IND'    | 'CV+68F5MZ05'(!)           = ''              | ''                 | 'CV+68F5MZ05'              |'L_PCMC063T'| '0.68UH'                       | 'DISCRETE' | 'IND SMD 0.68U +-20%,15.5A PCMC063T-R68MN'      | 'CHIP'         | ''          | ''   | '20110221'  
 '0.68UH'                       | 'SMLF'     | 'EMPTY'  | 'CV+68F5MZ05'(!)           = ''              | ''                 | 'CV+68F5MZ05'              |'L_PCMC063T'| 'NA'                           | 'IO'       | 'IND SMD 0.68U +-20%,15.5A PCMC063T-R68MN'      | 'CHIP'         | ''          | ''   | '20110221'  
 '0.68UH'                       | 'SMLF'     | 'IND'    | 'CV+68Z0MZ02'(!)           = ''              | ''                 | 'CV+68Z0MZ02'              |'L_PCMC135T'| '0.68UH'                       | 'DISCRETE' | 'IND SMD 0.68UH +-20% 34A(PCMC135T-R68MF) '     | 'CHIP'         | ''          | ''   | '20110221'  
 '0.68UH'                       | 'SMLF'     | 'EMPTY'  | 'CV+68Z0MZ02'(!)           = ''              | ''                 | 'CV+68Z0MZ02'              |'L_PCMC135T'| 'NA'                           | 'IO'       | 'IND SMD 0.68UH +-20% 34A(PCMC135T-R68MF) '     | 'CHIP'         | ''          | ''   | '20110221'  
 '0.82UH'                       | 'SMLF'     | 'IND'    | 'CV+82D0MZ04'(!)           = ''              | ''                 | 'CV+82D0MZ04'              |'L_PCMC063T'| '0.82UH'                       | 'DISCRETE' | 'IND SMD 0.82UH +-20% 13A(PCMC063T-R82MN)'      | 'CHIP'         | ''          | ''   | '20110221'  
 '0.82UH'                       | 'SMLF'     | 'EMPTY'  | 'CV+82D0MZ04'(!)           = ''              | ''                 | 'CV+82D0MZ04'              |'L_PCMC063T'| 'NA'                           | 'IO'       | 'IND SMD 0.82UH +-20% 13A(PCMC063T-R82MN)'      | 'CHIP'         | ''          | ''   | '20110221'  
 '10UH'                         | 'SMLF'     | 'IND'    | 'CV01060MZ00'(!)           = ''              | ''                 | 'CV01060MZ00'              |'L_PCMB104TXB'| '10UH'                         | 'DISCRETE' | 'IND SMD 10UH +-20% 6A(PCMB104T-100MS)'         | 'CHIP'         | ''          | ''   | '20110221'  
 '10UH'                         | 'SMLF'     | 'EMPTY'  | 'CV01060MZ00'(!)           = ''              | ''                 | 'CV01060MZ00'              |'L_PCMB104TXB'| 'NA'                           | 'IO'       | 'IND SMD 10UH +-20% 6A(PCMB104T-100MS)'         | 'CHIP'         | ''          | ''   | '20110221'  
 '1UH'                          | 'SMLF'     | 'IND'    | 'CV-10B0MZ13'(!)           = ''              | ''                 | 'CV-10B0MZ13'              |'L_PCMC063T'| '1UH'                          | 'DISCRETE' | 'IND SMD 1UH 20%11A(PCMC063T-1R0MN)'            | 'CHIP'         | ''          | ''   | '20110221'  
 '1UH'                          | 'SMLF'     | 'EMPTY'  | 'CV-10B0MZ13'(!)           = ''              | ''                 | 'CV-10B0MZ13'              |'L_PCMC063T'| 'NA'                           | 'IO'       | 'IND SMD 1UH 20%11A(PCMC063T-1R0MN)'            | 'CHIP'         | ''          | ''   | '20110221'  
 '1.0UH'                        | 'SMLF'     | 'IND'    | 'CV-10I0MZ04'(!)           = ''              | ''                 | 'CV-10I0MZ04'              |'L_PCMB104TXA'| '1.0UH'                        | 'DISCRETE' | 'IND SMD 1.0UH +-20% 18A(PCMB104T-1R0MS)'       | 'CHIP'         | ''          | ''   | '20110221'  
 '1.0UH'                        | 'SMLF'     | 'EMPTY'  | 'CV-10I0MZ04'(!)           = ''              | ''                 | 'CV-10I0MZ04'              |'L_PCMB104TXA'| 'NA'                           | 'IO'       | 'IND SMD 1.0UH +-20% 18A(PCMB104T-1R0MS)'       | 'CHIP'         | ''          | ''   | '20110221'  
 '1UH'                          | 'SMLF'     | 'IND'    | 'CV-10U0MZ01'(!)           = ''              | ''                 | 'CV-10U0MZ01'              |'L_PCMC135T'| '1UH'                          | 'DISCRETE' | 'IND SMD 1UH +-20% 29A(PCMC135T-1R0MF)'         | 'CHIP'         | ''          | ''   | '20110221'  
 '1UH'                          | 'SMLF'     | 'EMPTY'  | 'CV-10U0MZ01'(!)           = ''              | ''                 | 'CV-10U0MZ01'              |'L_PCMC135T'| 'NA'                           | 'IO'       | 'IND SMD 1UH +-20% 29A(PCMC135T-1R0MF)'         | 'CHIP'         | ''          | ''   | '20110221'  
 '1.5UH'                        | 'SMLF'     | 'IND'    | 'CV-15G0MZ01'(!)           = ''              | ''                 | 'CV-15G0MZ01'              |'L_PCMB104TXA'| '1.5UH'                        | 'DISCRETE' | 'IND SMD 1.5UH +-20% 16A(PCMB104T-1R5MS)'       | 'CHIP'         | ''          | ''   | '20110221'  
 '1.5UH'                        | 'SMLF'     | 'EMPTY'  | 'CV-15G0MZ01'(!)           = ''              | ''                 | 'CV-15G0MZ01'              |'L_PCMB104TXA'| 'NA'                           | 'IO'       | 'IND SMD 1.5UH +-20% 16A(PCMB104T-1R5MS)'       | 'CHIP'         | ''          | ''   | '20110221'  
 '1.5UH'                        | 'SMLF'     | 'IND'    | 'CV-15I0MZ28'(!)           = ''              | ''                 | 'CV-15I0MZ28'              |'L_PCMC063T'| '1.5UH'                        | 'DISCRETE' | 'IND SMD 1.5UH+-20% 18A(PCMC063T-1R5MN)'        | 'CHIP'         | ''          | ''   | '20110221'  
 '1.5UH'                        | 'SMLF'     | 'EMPTY'  | 'CV-15I0MZ28'(!)           = ''              | ''                 | 'CV-15I0MZ28'              |'L_PCMC063T'| 'NA'                           | 'IO'       | 'IND SMD 1.5UH+-20% 18A(PCMC063T-1R5MN)'        | 'CHIP'         | ''          | ''   | '20110221'  
 '1.5UH'                        | 'SMLF'     | 'IND'    | 'CV-15N0MZ02'(!)           = ''              | ''                 | 'CV-15N0MZ02'              |'L_PCMC135T'| '1.5UH'                        | 'DISCRETE' | 'IND SMD 1.5UH 23A,+-20%(PCMC135T-1R5MF)'       | 'CHIP'         | ''          | ''   | '20110221'  
 '1.5UH'                        | 'SMLF'     | 'EMPTY'  | 'CV-15N0MZ02'(!)           = ''              | ''                 | 'CV-15N0MZ02'              |'L_PCMC135T'| 'NA'                           | 'IO'       | 'IND SMD 1.5UH 23A,+-20%(PCMC135T-1R5MF)'       | 'CHIP'         | ''          | ''   | '20110221'  
 '2.2UH'                        | 'SMLF'     | 'IND'    | 'CV-2230MZ03'(!)           = ''              | ''                 | 'CV-2230MZ03'              |'L_PCMB042T'| '2.2UH'                        | 'DISCRETE' | 'IND SMD 2.2UH +-20% 3A(PCMB042T-2R2MS)'        | 'CHIP'         | ''          | ''   | '20110221'  
 '2.2UH'                        | 'SMLF'     | 'EMPTY'  | 'CV-2230MZ03'(!)           = ''              | ''                 | 'CV-2230MZ03'              |'L_PCMB042T'| 'NA'                           | 'IO'       | 'IND SMD 2.2UH +-20% 3A(PCMB042T-2R2MS)'        | 'CHIP'         | ''          | ''   | '20110221'  
 '2.2UH'                        | 'SMLF'     | 'IND'    | 'CV-2280MZ15'(!)           = ''              | ''                 | 'CV-2280MZ15'              |'L_PCMC063T'| '2.2UH'                        | 'DISCRETE' | 'IND SMD 2.2UH +-20% 8A(PCMC063T-2R2MN)'        | 'CHIP'         | ''          | ''   | '20110221'  
 '2.2UH'                        | 'SMLF'     | 'EMPTY'  | 'CV-2280MZ15'(!)           = ''              | ''                 | 'CV-2280MZ15'              |'L_PCMC063T'| 'NA'                           | 'IO'       | 'IND SMD 2.2UH +-20% 8A(PCMC063T-2R2MN)'        | 'CHIP'         | ''          | ''   | '20110221'  
 '2.2UH'                        | 'SMLF'     | 'IND'    | 'CV-22C0MZ02'(!)           = ''              | ''                 | 'CV-22C0MZ02'              |'L_PCMB104TXB'| '2.2UH'                        | 'DISCRETE' | 'IND SMD 2.2UH+-20%12A(PCMB104T-2R2MN)'         | 'CHIP'         | ''          | ''   | '20110221'  
 '2.2UH'                        | 'SMLF'     | 'EMPTY'  | 'CV-22C0MZ02'(!)           = ''              | ''                 | 'CV-22C0MZ02'              |'L_PCMB104TXB'| 'NA'                           | 'IO'       | 'IND SMD 2.2UH+-20%12A(PCMB104T-2R2MN)'         | 'CHIP'         | ''          | ''   | '20110221'  
 '3.3UH'                        | 'SMLF'     | 'IND'    | 'CV-33B0MZ01'(!)           = ''              | ''                 | 'CV-33B0MZ01'              |'L_PCMB104TXB'| '3.3UH'                        | 'DISCRETE' | 'IND 3.3UH 11A +-20%(PCMB104E-3R3MS)'           | 'CHIP'         | ''          | ''   | '20110221'  
 '3.3UH'                        | 'SMLF'     | 'EMPTY'  | 'CV-33B0MZ01'(!)           = ''              | ''                 | 'CV-33B0MZ01'              |'L_PCMB104TXB'| 'NA'                           | 'IO'       | 'IND 3.3UH 11A +-20%(PCMB104E-3R3MS)'           | 'CHIP'         | ''          | ''   | '20110221'  
 '4.7UH'                        | 'SMLF'     | 'IND'    | 'CV-4755MZ12'(!)           = ''              | ''                 | 'CV-4755MZ12'              |'L_PCMC063T'| '4.7UH'                        | 'DISCRETE' | 'IND SMD 4.7U20%5.5A(PCMC063T-4R7MN)'           | 'CHIP'         | ''          | ''   | '20110221'  
 '4.7UH'                        | 'SMLF'     | 'EMPTY'  | 'CV-4755MZ12'(!)           = ''              | ''                 | 'CV-4755MZ12'              |'L_PCMC063T'| 'NA'                           | 'IO'       | 'IND SMD 4.7U20%5.5A(PCMC063T-4R7MN)'           | 'CHIP'         | ''          | ''   | '20110221'  
 '6.8UH'                        | 'SMLF'     | 'IND'    | 'CV-6845MZ05'(!)           = ''              | ''                 | 'CV-6845MZ05'              |'L_PCMC063T'| '6.8UH'                        | 'DISCRETE' | 'IND SMD 6.8UH +-20%,4.5A(PCMC063T-6R8MN)'      | 'CHIP'         | ''          | ''   | '20110221'  
 '6.8UH'                        | 'SMLF'     | 'EMPTY'  | 'CV-6845MZ05'(!)           = ''              | ''                 | 'CV-6845MZ05'              |'L_PCMC063T'| 'NA'                           | 'IO'       | 'IND SMD 6.8UH +-20%,4.5A(PCMC063T-6R8MN)'      | 'CHIP'         | ''          | ''   | '20110221'  
 '6.8UH'                        | 'SMLF'     | 'IND'    | 'CV-6865MZ02'(!)           = ''              | ''                 | 'CV-6865MZ02'              |'L_PCMB104TXB'| '6.8UH'                        | 'DISCRETE' | 'IND SMD 6.8UH +-20% 6.5A PCMB104T-6R8MS'       | 'CHIP'         | ''          | ''   | '20110221'  
 '6.8UH'                        | 'SMLF'     | 'EMPTY'  | 'CV-6865MZ02'(!)           = ''              | ''                 | 'CV-6865MZ02'              |'L_PCMB104TXB'| 'NA'                           | 'IO'       | 'IND SMD 6.8UH +-20% 6.5A PCMB104T-6R8MS'       | 'CHIP'         | ''          | ''   | '20110221'  
 '0.22UH'                       | 'SMLF'     | 'IND'    | 'TMP_TU1_KC_0303_2'(!)     = ''              | ''                 | 'TMP_TU1_KC_0303_2'        |'L_SI2C120609'| '0.22UH'                       | 'DISCRETE' | 'IND SMD 0.22UH +-10% 55A(SI2C120609-R22K-R27)' | 'CHIP'         | ''          | ''   | '20110303'  
 '0.22UH'                       | 'SMLF'     | 'EMPTY'  | 'TMP_TU1_KC_0303_2'(!)     = ''              | ''                 | 'TMP_TU1_KC_0303_2'        |'L_SI2C120609'| 'NA'                           | 'IO'       | 'IND SMD 0.22UH +-10% 55A(SI2C120609-R22K-R27)' | 'CHIP'         | ''          | ''   | '20110303'  
 '0.32UH'                       | 'SMLF'     | 'IND'    | 'CV+32^0KZ01'(!)           = ''              | ''                 | 'CV+32^0KZ01'              |'L_SI2C100709'| '0.32UH'                       | 'DISCRETE' | 'IND SMD 0.32U +-10% 35A(SI2C100709-R32K)'      | 'CHIP'         | ''          | ''   | '20110315'  
 '0.32UH'                       | 'SMLF'     | 'EMPTY'  | 'CV+32^0KZ01'(!)           = ''              | ''                 | 'CV+32^0KZ01'              |'L_SI2C100709'| 'NA'                           | 'IO'       | 'IND SMD 0.32U +-10% 35A(SI2C100709-R32K)'      | 'CHIP'         | ''          | ''   | '20110315'  
 '0.23UH'                       | 'SMLF'     | 'IND'    | 'CV+23^0EZ08'(!)           = ''              | ''                 | 'CV+23^0EZ08'              |'L_HCB137590271'| '0.23UH'                       | 'DISCRETE' | 'IND SMD 0.23UH +-15% 60A (HCB137590-231)'      | 'CHIP'         | ''          | ''   | '20110315'  
 '0.23UH'                       | 'SMLF'     | 'EMPTY'  | 'CV+23^0EZ08'(!)           = ''              | ''                 | 'CV+23^0EZ08'              |'L_HCB137590271'| 'NA'                           | 'IO'       | 'IND SMD 0.23UH +-15% 60A (HCB137590-231)'      | 'CHIP'         | ''          | ''   | '20110315'  
 '2.7UH'                        | 'SMLF'     | 'IND'    | 'CV-2703KN01'(!)           = ''              | ''                 | 'CV-2703KN01'              |'L0805'| '2.7UH'                        | 'DISCRETE' | 'IND 2.7UH+-10% 30MA GMLI-201209-2R7K'          | 'CHIP'         | ''          | ''   | '20110329'  
 '2.7UH'                        | 'SMLF'     | 'EMPTY'  | 'CV-2703KN01'(!)           = ''              | ''                 | 'CV-2703KN01'              |'L0805'| 'NA'                           | 'IO'       | 'IND 2.7UH+-10% 30MA GMLI-201209-2R7K'          | 'CHIP'         | ''          | ''   | '20110329'  
 '1.5UH'                        | 'SMLF'     | 'IND'    | 'CV-15G0MZ03'(!)           = ''              | ''                 | 'CV-15G0MZ03'              |'L_PCMC104T'| '1.5UH'                        | 'DISCRETE' | 'IND SMD 1.5UH +-20% 16A(PCMC104T-1R5MN)'       | 'CHIP'         | ''          | ''   | '20110330'  
 '1.5UH'                        | 'SMLF'     | 'EMPTY'  | 'CV-15G0MZ03'(!)           = ''              | ''                 | 'CV-15G0MZ03'              |'L_PCMC104T'| 'NA'                           | 'IO'       | 'IND SMD 1.5UH +-20% 16A(PCMC104T-1R5MN)'       | 'CHIP'         | ''          | ''   | '20110330'  
 '250NH'                        | 'SMLF'     | 'IND'    | 'CV+25^0EZ00'(!)           = ''              | ''                 | 'CV+25^0EZ00'              |'L_HCB1190B'| '250NH'                        | 'DISCRETE' | 'IND SMD 250NH +-15% 42A(HCB1190-251L-F)'       | 'CHIP'         | ''          | ''   | '20110510'  
 '250NH'                        | 'SMLF'     | 'EMPTY'  | 'CV+25^0EZ00'(!)           = ''              | ''                 | 'CV+25^0EZ00'              |'L_HCB1190B'| 'NA'                           | 'IO'       | 'IND SMD 250NH +-15% 42A(HCB1190-251L-F)'       | 'CHIP'         | ''          | ''   | '20110510'  
 '0.38UH'                       | 'SMLF'     | 'IND'    | 'CV+38^0EZ01'(!)           = ''              | ''                 | 'CV+38^0EZ01'              |'L_HCB1190381LF'| '0.38UH'                       | 'DISCRETE' | 'IND SMD 0.38U 15% 45A(HCB1190-381L-F)'         | 'CHIP'         | ''          | ''   | '20110812'  
 '0.38UH'                       | 'SMLF'     | 'EMPTY'  | 'CV+38^0EZ01'(!)           = ''              | ''                 | 'CV+38^0EZ01'              |'L_HCB1190381LF'| 'NA'                           | 'IO'       | 'IND SMD 0.38U 15% 45A(HCB1190-381L-F)'         | 'CHIP'         | ''          | ''   | '20110812'  
 '1.0UH'                        | 'SMLF'     | 'IND'    | 'CV-1070MZ09'(!)           = ''              | ''                 | 'CV-1070MZ09'              |'L_PCMB042T'| '1.0UH'                        | 'DISCRETE' | 'IND SMD 1.0UH 20% 7A(PCMB042T-1R0MS)'          | 'CHIP'         | ''          | ''   | '20110923'  
 '1.0UH'                        | 'SMLF'     | 'EMPTY'  | 'CV-1070MZ09'(!)           = ''              | ''                 | 'CV-1070MZ09'              |'L_PCMB042T'| 'NA'                           | 'IO'       | 'IND SMD 1.0UH 20% 7A(PCMB042T-1R0MS)'          | 'CHIP'         | ''          | ''   | '20110923'  
 'FCM2012CF-121T06'             | 'SMLF'     | 'IND'    | 'CX000121307'(!)           = ''              | ''                 | 'CX000121307'              |'L0805'| 'FCM2012CF-121T06'             | 'DISCRETE' | 'EMI FILTER FCM2012CF-121T06(600MA)'            | 'CHIP'         | ''          | ''   | '2011/11/25'
 'FCM2012CF-121T06'             | 'SMLF'     | 'EMPTY'  | 'CX000121307'(!)           = ''              | ''                 | 'CX000121307'              |'L0805'| 'NA'                           | 'IO'       | 'EMI FILTER FCM2012CF-121T06(600MA)'            | 'CHIP'         | ''          | ''   | '2011/11/25'
 '0.25U/34.5A'                  | 'THLF'     | 'IND'    | 'DC+25^0K000'(!)           = ''              | ''                 | 'DC+25^0K000'              |'L_AI2C110510'| '0.25U/34.5A'                  | 'DISCRETE' | 'CHOKE 0.25U +-10% 34.5A AI2C110510-R25K'       | 'CHIP'         | ''          | ''   | '20111130'  
 '0.25U/34.5A'                  | 'THLF'     | 'EMPTY'  | 'DC+25^0K000'(!)           = ''              | ''                 | 'DC+25^0K000'              |'L_AI2C110510'| 'NA'                           | 'IO'       | 'CHOKE 0.25U +-10% 34.5A AI2C110510-R25K'       | 'CHIP'         | ''          | ''   | '20111130'  
 '0.25U/45A'                    | 'SMLF'     | 'IND'    | 'CV+25^0KZ00'(!)           = ''              | ''                 | 'CV+25^0KZ00'              |'L_SI2C100709'| '0.25U/45A'                    | 'DISCRETE' | 'IND SMD 0.25U +-10% 45A(SI2C100709-R25K)'      | 'CHIP'         | ''          | ''   | '20111130'  
 '0.25U/45A'                    | 'SMLF'     | 'EMPTY'  | 'CV+25^0KZ00'(!)           = ''              | ''                 | 'CV+25^0KZ00'              |'L_SI2C100709'| 'NA'                           | 'IO'       | 'IND SMD 0.25U +-10% 45A(SI2C100709-R25K)'      | 'CHIP'         | ''          | ''   | '20111130'  
 '1000/0.2A'                    | 'SMLF'     | 'IND'    | 'CX1AG102000'(!)           = ''              | ''                 | 'CX1AG102000'              |'L0805'| '1000/0.2A'                    | 'DISCRETE' | 'EMI FILTER BLM21AG102SN1D(1000,0.2A)'          | 'CHIP'         | ''          | ''   | '20111212'  
 '1000/0.2A'                    | 'SMLF'     | 'EMPTY'  | 'CX1AG102000'(!)           = ''              | ''                 | 'CX1AG102000'              |'L0805'| 'NA'                           | 'IO'       | 'EMI FILTER BLM21AG102SN1D(1000,0.2A)'          | 'CHIP'         | ''          | ''   | '20111212'  
 '3.3UH/2A'                     | 'SMLF'     | 'IND'    | 'CV-3320MZ04'(!)           = ''              | ''                 | 'CV-3320MZ04'              |'L_WQPC0403'| '3.3UH/2A'                     | 'DISCRETE' | 'IND SMD 3.3UH,+-20% 2A(WQPC0403)'              | 'CHIP'         | ''          | ''   | '20111214'  
 '3.3UH/2A'                     | 'SMLF'     | 'EMPTY'  | 'CV-3320MZ04'(!)           = ''              | ''                 | 'CV-3320MZ04'              |'L_WQPC0403'| 'NA'                           | 'IO'       | 'IND SMD 3.3UH,+-20% 2A(WQPC0403)'              | 'CHIP'         | ''          | ''   | '20111214'  
 '1UH/15.3A'                    | 'SMLF'     | 'IND'    | 'CV-10F3MZ00'(!)           = ''              | ''                 | 'CV-10F3MZ00'              |'L_SPM6550T'| '1UH/15.3A'                    | 'DISCRETE' | 'IND SMD 1UH 20% 15.3A(SPM6550T-1R0M100A)'      | 'CHIP'         | ''          | ''   | '20111215'  
 '1UH/15.3A'                    | 'SMLF'     | 'EMPTY'  | 'CV-10F3MZ00'(!)           = ''              | ''                 | 'CV-10F3MZ00'              |'L_SPM6550T'| 'NA'                           | 'IO'       | 'IND SMD 1UH 20% 15.3A(SPM6550T-1R0M100A)'      | 'CHIP'         | ''          | ''   | '20111215'  
 '4.7UH/1.7A'                   | 'SMLF'     | 'IND'    | 'CV-4717TZ00'(!)           = 'Non-Preferred' | 'End of Life'      | 'CV-4717TZ00'              |'L_SIL620_EOL'| '4.7UH/1.7A'                   | 'DISCRETE' | 'IND SMD 4.7UH+-30%,1.7A(SIL620-4R7)'           | 'CHIP'         | ''          | ''   | '20111219'  
 '4.7UH/1.7A'                   | 'SMLF'     | 'EMPTY'  | 'CV-4717TZ00'(!)           = 'Non-Preferred' | 'End of Life'      | 'CV-4717TZ00'              |'L_SIL620_EOL'| 'NA'                           | 'IO'       | 'IND SMD 4.7UH+-30%,1.7A(SIL620-4R7)'           | 'CHIP'         | ''          | ''   | '20111219'  
 '3.3UH/6.6A'                   | 'SMLF'     | 'IND'    | 'TMP_S4E_JHIH-RONG_1219_1'(!) = ''              | ''                 | 'TMP_S4E_JHIH-RONG_1219_1' |'L_CLF10040T'| '3.3UH/6.6A'                   | 'DISCRETE' | 'IND SMD 3.3UH 30%  6.6A(CLF10040T-3R3N)'       | 'CHIP'         | ''          | ''   | '20111219'  
 '3.3UH/6.6A'                   | 'SMLF'     | 'EMPTY'  | 'TMP_S4E_JHIH-RONG_1219_1'(!) = ''              | ''                 | 'TMP_S4E_JHIH-RONG_1219_1' |'L_CLF10040T'| 'NA'                           | 'IO'       | 'IND SMD 3.3UH 30%  6.6A(CLF10040T-3R3N)'       | 'CHIP'         | ''          | ''   | '20111219'  
 '800/8A'                       | 'SMLF'     | 'IND'    | 'CX0V801R000'(!)           = 'End of Design' | 'Comp-Approve'     | 'CX0V801R000'              |'L_HR2220V801R'| '800/8A'                       | 'DISCRETE' | 'EMI FILTER HR2220V801R-10 (800.8A)'            | 'CHIP'         | ''          | ''   | '20111220'  
 '800/8A'                       | 'SMLF'     | 'EMPTY'  | 'CX0V801R000'(!)           = 'End of Design' | 'Comp-Approve'     | 'CX0V801R000'              |'L_HR2220V801R'| 'NA'                           | 'IO'       | 'EMI FILTER HR2220V801R-10 (800.8A)'            | 'CHIP'         | ''          | ''   | '20111220'  
 '1.1UH/3.7A'                   | 'SMLF'     | 'IND'    | 'CV-1137TZ00'(!)           = ''              | 'End of Life'      | 'CV-1137TZ00'              |'L_SIL620_EOL'| '1.1UH/3.7A'                   | 'DISCRETE' | 'IND SMD 1.1UH +-30% 3.7A(SIL620-1R1)'          | 'CHIP'         | ''          | ''   | '20120105'  
 '1.1UH/3.7A'                   | 'SMLF'     | 'EMPTY'  | 'CV-1137TZ00'(!)           = ''              | 'End of Life'      | 'CV-1137TZ00'              |'L_SIL620_EOL'| 'NA'                           | 'IO'       | 'IND SMD 1.1UH +-30% 3.7A(SIL620-1R1)'          | 'CHIP'         | ''          | ''   | '20120105'  
 '0.1UH/35A'                    | 'SMLF'     | 'IND'    | 'CV+10^0MZ04'(!)           = 'Non-Preferred' | 'End of Life'      | 'CV+10^0MZ04'              |'L_SIHC060675R10MR23_EOL'| '0.1UH/35A'                    | 'DISCRETE' | 'IND SMD 0.1UH,+-20%,35A SIHC060675-R10M'       | 'CHIP'         | ''          | ''   | '20120112'  
 '0.1UH/35A'                    | 'SMLF'     | 'EMPTY'  | 'CV+10^0MZ04'(!)           = 'Non-Preferred' | 'End of Life'      | 'CV+10^0MZ04'              |'L_SIHC060675R10MR23_EOL'| 'NA'                           | 'IO'       | 'IND SMD 0.1UH,+-20%,35A SIHC060675-R10M'       | 'CHIP'         | ''          | ''   | '20120112'  
 '0.18UH/54A'                   | 'SMLF'     | 'IND'    | 'CV+18^0KZ01'(!)           = 'Non-Preferred' | 'End of Life'      | 'CV+18^0KZ01'              |'L_SL4330B_EOL'| '0.18UH/54A'                   | 'DISCRETE' | 'IND SMD 0.18UH +-10% 54A(SL4330B-R18KU)'       | 'CHIP'         | ''          | ''   | '20120112'  
 '0.18UH/54A'                   | 'SMLF'     | 'EMPTY'  | 'CV+18^0KZ01'(!)           = 'Non-Preferred' | 'End of Life'      | 'CV+18^0KZ01'              |'L_SL4330B_EOL'| 'NA'                           | 'IO'       | 'IND SMD 0.18UH +-10% 54A(SL4330B-R18KU)'       | 'CHIP'         | ''          | ''   | '20120112'  
 '1.5UH/18A'                    | 'SMLF'     | 'IND'    | 'CV-15I0MZ08'(!)           = 'End of Design' | 'Comp-Approve'     | 'CV-15I0MZ08'              |'L_MPT730'| '1.5UH/18A'                    | 'DISCRETE' | 'IND SMD 1.5UH+-20% 18A(MPT730-1R5M1IN)'        | 'CHIP'         | ''          | ''   | '20120112'  
 '1.5UH/18A'                    | 'SMLF'     | 'EMPTY'  | 'CV-15I0MZ08'(!)           = 'End of Design' | 'Comp-Approve'     | 'CV-15I0MZ08'              |'L_MPT730'| 'NA'                           | 'IO'       | 'IND SMD 1.5UH+-20% 18A(MPT730-1R5M1IN)'        | 'CHIP'         | ''          | ''   | '20120112'  
 '2.2UH/14A'                    | 'SMLF'     | 'IND'    | 'CV-22E0MZ15'(!)           = ''              | ''                 | 'CV-22E0MZ15'              |'L_PCMB104E'| '2.2UH/14A'                    | 'DISCRETE' | 'IND SMD 2.2UH +-20% 14A(PCMB104E-2R2MS)'       | 'CHIP'         | ''          | ''   | '20120118'  
 '2.2UH/14A'                    | 'SMLF'     | 'EMPTY'  | 'CV-22E0MZ15'(!)           = ''              | ''                 | 'CV-22E0MZ15'              |'L_PCMB104E'| 'NA'                           | 'IO'       | 'IND SMD 2.2UH +-20% 14A(PCMB104E-2R2MS)'       | 'CHIP'         | ''          | ''   | '20120118'  
 '220NH/60A'                    | 'SMLF'     | 'IND'    | 'CV+22^0MZ08'(!)           = ''              | ''                 | 'CV+22^0MZ08'              |'L_HCB117590'| '220NH/60A'                    | 'DISCRETE' | 'IND SMD 220NH 20% 60A(HCB117590-221G)'         | 'CHIP'         | ''          | ''   | '20120131'  
 '220NH/60A'                    | 'SMLF'     | 'EMPTY'  | 'CV+22^0MZ08'(!)           = ''              | ''                 | 'CV+22^0MZ08'              |'L_HCB117590'| 'NA'                           | 'IO'       | 'IND SMD 220NH 20% 60A(HCB117590-221G)'         | 'CHIP'         | ''          | ''   | '20120131'  
 '33UH/4.3A'                    | 'SMLF'     | 'IND'    | 'CV03343MZ00'(!)           = ''              | ''                 | 'CV03343MZ00'              |'L_MSCDRI127A'| '33UH/4.3A'                    | 'DISCRETE' | 'IND SMD 33UH 20% 4.3A (MSCDRI-127A-330M)'      | 'CHIP'         | ''          | ''   | '20120209'  
 '33UH/4.3A'                    | 'SMLF'     | 'EMPTY'  | 'CV03343MZ00'(!)           = ''              | ''                 | 'CV03343MZ00'              |'L_MSCDRI127A'| 'NA'                           | 'IO'       | 'IND SMD 33UH 20% 4.3A (MSCDRI-127A-330M)'      | 'CHIP'         | ''          | ''   | '20120209'  
 '4.7UH/12A'                    | 'SMLF'     | 'IND'    | 'CV-47C0MZ01'(!)           = ''              | ''                 | 'CV-47C0MZ01'              |'L_PCMC135TXA'| '4.7UH/12A'                    | 'DISCRETE' | 'IND SMD 4.7UH +-20% 12A(PCMC135T-4R7MF)'       | 'CHIP'         | ''          | ''   | '20120215'  
 '4.7UH/12A'                    | 'SMLF'     | 'EMPTY'  | 'CV-47C0MZ01'(!)           = ''              | ''                 | 'CV-47C0MZ01'              |'L_PCMC135TXA'| 'NA'                           | 'IO'       | 'IND SMD 4.7UH +-20% 12A(PCMC135T-4R7MF)'       | 'CHIP'         | ''          | ''   | '20120215'  
 '10UH/125MA'                   | 'SMLF'     | 'IND'    | 'CV01002MN03'(!)           = ''              | ''                 | 'CV01002MN03'              |'L0805_H56'| '10UH/125MA'                   | 'DISCRETE' | 'IND 10UH, 20%,125MA LBR2012T100M'              | 'CHIP'         | ''          | ''   | '20120221'  
 '10UH/125MA'                   | 'SMLF'     | 'EMPTY'  | 'CV01002MN03'(!)           = ''              | ''                 | 'CV01002MN03'              |'L0805_H56'| 'NA'                           | 'IO'       | 'IND 10UH, 20%,125MA LBR2012T100M'              | 'CHIP'         | ''          | ''   | '20120221'  
 '100UH/315MA'                  | 'SMLF'     | 'IND'    | 'CV11004MZ00'(!)           = ''              | ''                 | 'CV11004MZ00'              |'L_MNR-3015'| '100UH/315MA'                  | 'DISCRETE' | 'IND SMD 100UH 20% 315MA(MNR-3015-101M-E)'      | 'CHIP'         | ''          | ''   | '20120306'  
 '100UH/315MA'                  | 'SMLF'     | 'EMPTY'  | 'CV11004MZ00'(!)           = ''              | ''                 | 'CV11004MZ00'              |'L_MNR-3015'| 'NA'                           | 'IO'       | 'IND SMD 100UH 20% 315MA(MNR-3015-101M-E)'      | 'CHIP'         | ''          | ''   | '20120306'  
 '0.36UH/30A'                   | 'SMLF'     | 'IND'    | 'CV+18V0MZ04'(!)           = ''              | ''                 | 'CV+18V0MZ04'              |'L_ETQP4LR36'| '0.36UH/30A'                   | 'DISCRETE' | 'IND SMD 0.36UH +-20% 30A(ETQP4LR36WFC)'        | 'CHIP'         | ''          | ''   | '20120307'  
 '0.36UH/30A'                   | 'SMLF'     | 'EMPTY'  | 'CV+18V0MZ04'(!)           = ''              | ''                 | 'CV+18V0MZ04'              |'L_ETQP4LR36'| 'NA'                           | 'IO'       | 'IND SMD 0.36UH +-20% 30A(ETQP4LR36WFC)'        | 'CHIP'         | ''          | ''   | '20120307'  
 '0.36UH/28A'                   | 'SMLF'     | 'IND'    | 'CV+36T0MZ01'(!)           = ''              | ''                 | 'CV+36T0MZ01'              |'L_ETQP4LR36'| '0.36UH/28A'                   | 'DISCRETE' | 'IND SMD 0.36U +-20%,28A(ETQP4LR36AFC)'         | 'CHIP'         | ''          | ''   | '20120307'  
 '0.36UH/28A'                   | 'SMLF'     | 'EMPTY'  | 'CV+36T0MZ01'(!)           = ''              | ''                 | 'CV+36T0MZ01'              |'L_ETQP4LR36'| 'NA'                           | 'IO'       | 'IND SMD 0.36U +-20%,28A(ETQP4LR36AFC)'         | 'CHIP'         | ''          | ''   | '20120307'  
 '0.1UH/35A'                    | 'SMLF'     | 'IND'    | 'CV+10^0MZ05'(!)           = ''              | ''                 | 'CV+10^0MZ05'              |'L_MSI-600608'| '0.1UH/35A'                    | 'DISCRETE' | 'IND SMD 0.1UH +-20% 35A MSI-600608-R10M'       | 'CHIP'         | ''          | ''   | '20120314'  
 '0.1UH/35A'                    | 'SMLF'     | 'EMPTY'  | 'CV+10^0MZ05'(!)           = ''              | ''                 | 'CV+10^0MZ05'              |'L_MSI-600608'| 'NA'                           | 'IO'       | 'IND SMD 0.1UH +-20% 35A MSI-600608-R10M'       | 'CHIP'         | ''          | ''   | '20120314'  
 '0.2UH/35A'                    | 'SMLF'     | 'IND'    | 'CV+20^0MZ04'(!)           = ''              | ''                 | 'CV+20^0MZ04'              |'L_MSI-600608'| '0.2UH/35A'                    | 'DISCRETE' | 'IND SMD 0.2UH +-20% 35A(MSI-600608-R20M'       | 'CHIP'         | ''          | ''   | '20120314'  
 '0.2UH/35A'                    | 'SMLF'     | 'EMPTY'  | 'CV+20^0MZ04'(!)           = ''              | ''                 | 'CV+20^0MZ04'              |'L_MSI-600608'| 'NA'                           | 'IO'       | 'IND SMD 0.2UH +-20% 35A(MSI-600608-R20M'       | 'CHIP'         | ''          | ''   | '20120314'  
 '0.1UH/18A'                    | 'SMLF'     | 'IND'    | 'TMP_T2L_KC_0316_1'(!)     = ''              | ''                 | 'TMP_T2L_KC_0316_1'        |'L_SIFH040406'| '0.1UH/18A'                    | 'DISCRETE' | 'IND SMD 0.1UH.+-20%18A(SIFH040406-R10M'        | 'CHIP'         | ''          | ''   | '20120316'  
 '0.1UH/18A'                    | 'SMLF'     | 'EMPTY'  | 'TMP_T2L_KC_0316_1'(!)     = ''              | ''                 | 'TMP_T2L_KC_0316_1'        |'L_SIFH040406'| 'NA'                           | 'IO'       | 'IND SMD 0.1UH.+-20%18A(SIFH040406-R10M'        | 'CHIP'         | ''          | ''   | '20120316'  
 '0.1UH/20A'                    | 'SMLF'     | 'IND'    | 'TMP_T2L_KC_0316_2'(!)     = ''              | ''                 | 'TMP_T2L_KC_0316_2'        |'L_IUT0406'| '0.1UH/20A'                    | 'DISCRETE' | 'IND SMD 0.1UH.+-20%20A(IUT0406-R10M'           | 'CHIP'         | ''          | ''   | '20120316'  
 '0.1UH/20A'                    | 'SMLF'     | 'EMPTY'  | 'TMP_T2L_KC_0316_2'(!)     = ''              | ''                 | 'TMP_T2L_KC_0316_2'        |'L_IUT0406'| 'NA'                           | 'IO'       | 'IND SMD 0.1UH.+-20%20A(IUT0406-R10M'           | 'CHIP'         | ''          | ''   | '20120316'  
 '0.1UH/12A'                    | 'SMLF'     | 'IND'    | 'TMP_T2L_KC_0319_1'(!)     = ''              | ''                 | 'TMP_T2L_KC_0319_1'        |'L_PCMB042T'| '0.1UH/12A'                    | 'DISCRETE' | 'IND SMD 0.1UH +-20% 12A(PCMB042T-R10MS)'       | 'CHIP'         | ''          | ''   | '20120319'  
 '0.1UH/12A'                    | 'SMLF'     | 'EMPTY'  | 'TMP_T2L_KC_0319_1'(!)     = ''              | ''                 | 'TMP_T2L_KC_0319_1'        |'L_PCMB042T'| 'NA'                           | 'IO'       | 'IND SMD 0.1UH +-20% 12A(PCMB042T-R10MS)'       | 'CHIP'         | ''          | ''   | '20120319'  
 '0.215UH/40A'                  | 'SMLF'     | 'IND'    | 'CV+21^0MZ03'(!)           = ''              | ''                 | 'CV+21^0MZ03'              |'L_HCB1065'| '0.215UH/40A'                  | 'DISCRETE' | 'IND SMD 0.215UH +-20% 40A(HCB1065-211)'        | 'CHIP'         | ''          | ''   | '20120320'  
 '0.215UH/40A'                  | 'SMLF'     | 'EMPTY'  | 'CV+21^0MZ03'(!)           = ''              | ''                 | 'CV+21^0MZ03'              |'L_HCB1065'| 'NA'                           | 'IO'       | 'IND SMD 0.215UH +-20% 40A(HCB1065-211)'        | 'CHIP'         | ''          | ''   | '20120320'  
 '3.3UH/2.15A'                  | 'SMLF'     | 'IND'    | 'CV-3322MZ02'(!)           = ''              | ''                 | 'CV-3322MZ02'              |'L_MSCD43XA'| '3.3UH/2.15A'                  | 'DISCRETE' | 'IND SMD 3.3UH +-20% 2.15A MSCD-43-3R3M-F'      | 'CHIP'         | ''          | ''   | '20120322'  
 '3.3UH/2.15A'                  | 'SMLF'     | 'EMPTY'  | 'CV-3322MZ02'(!)           = ''              | ''                 | 'CV-3322MZ02'              |'L_MSCD43XA'| 'NA'                           | 'IO'       | 'IND SMD 3.3UH +-20% 2.15A MSCD-43-3R3M-F'      | 'CHIP'         | ''          | ''   | '20120322'  
 '6.8UH/11A'                    | 'SMLF'     | 'IND'    | 'CV-68B0MZ00'(!)           = ''              | ''                 | 'CV-68B0MZ00'              |'L_MMD12EZXA'| '6.8UH/11A'                    | 'DISCRETE' | 'IND SMD 6.8UH +-20% 11A(MMD-12EZ-6R8M-V1'      | 'CHIP'         | ''          | ''   | '20120325'  
 '6.8UH/11A'                    | 'SMLF'     | 'EMPTY'  | 'CV-68B0MZ00'(!)           = ''              | ''                 | 'CV-68B0MZ00'              |'L_MMD12EZXA'| 'NA'                           | 'IO'       | 'IND SMD 6.8UH +-20% 11A(MMD-12EZ-6R8M-V1'      | 'CHIP'         | ''          | ''   | '20120325'  
 '330/2.5A'                     | 'SMLF'     | 'IND'    | 'CX12S331000'(!)           = 'End of Design' | 'End of Life'      | 'CX12S331000'              |'L0805_EOL'| '330/2.5A'                     | 'DISCRETE' | 'EMI FILTER MPZ2012S331AT(330,2.5A,0805)'       | 'CHIP'         | ''          | ''   | '20120323'  
 '330/2.5A'                     | 'SMLF'     | 'EMPTY'  | 'CX12S331000'(!)           = 'End of Design' | 'End of Life'      | 'CX12S331000'              |'L0805_EOL'| 'NA'                           | 'IO'       | 'EMI FILTER MPZ2012S331AT(330,2.5A,0805)'       | 'CHIP'         | ''          | ''   | '20120323'  
 '100UH/1.25A'                  | 'SMLF'     | 'IND'    | 'CV11013MZ00'(!)           = ''              | ''                 | 'CV11013MZ00'              |'L_MSCDRI104RXA'| '330/2.5A'                     | 'DISCRETE' | 'IND SMD 100UH 20% 1.25A MSCDRI-104R-101M'      | 'CHIP'         | ''          | ''   | '20120326'  
 '100UH/1.25A'                  | 'SMLF'     | 'EMPTY'  | 'CV11013MZ00'(!)           = ''              | ''                 | 'CV11013MZ00'              |'L_MSCDRI104RXA'| 'NA'                           | 'IO'       | 'IND SMD 100UH 20% 1.25A MSCDRI-104R-101M'      | 'CHIP'         | ''          | ''   | '20120326'  
 '1UH/32A'                      | 'SMLF'     | 'IND'    | 'CV-10X0MZ00'(!)           = ''              | ''                 | 'CV-10X0MZ00'              |'L_MMD12FD'| '1UH/32A'                      | 'DISCRETE' | 'IND SMD 1UH +-20% 32A MMD-12FD-1R0M-V1Q'       | 'CHIP'         | ''          | ''   | '20120326'  
 '1UH/32A'                      | 'SMLF'     | 'EMPTY'  | 'CV-10X0MZ00'(!)           = ''              | ''                 | 'CV-10X0MZ00'              |'L_MMD12FD'| 'NA'                           | 'IO'       | 'IND SMD 1UH +-20% 32A MMD-12FD-1R0M-V1Q'       | 'CHIP'         | ''          | ''   | '20120326'  
 '0.1UH/12A'                    | 'SMLF'     | 'IND'    | 'CV+10C0MZ00'(!)           = ''              | ''                 | 'CV+10C0MZ00'              |'L_PCMB042T'| '0.1UH/12A'                    | 'DISCRETE' | 'IND SMD 0.1UH +-20% 12A(PCMB042T-R10MS)'       | 'CHIP'         | ''          | ''   | '20120326'  
 '0.1UH/12A'                    | 'SMLF'     | 'EMPTY'  | 'CV+10C0MZ00'(!)           = ''              | ''                 | 'CV+10C0MZ00'              |'L_PCMB042T'| 'NA'                           | 'IO'       | 'IND SMD 0.1UH +-20% 12A(PCMB042T-R10MS)'       | 'CHIP'         | ''          | ''   | '20120326'  
 '350NH/65A'                    | 'SMLF'     | 'IND'    | 'CV+35^0MZ00'(!)           = ''              | ''                 | 'CV+35^0MZ00'              |'L_HCBD101195451G'| '350NH/65A'                    | 'DISCRETE' | 'IND SMD 350NH +-20% 65A(HCBD101195-351G)'      | 'CHIP'         | ''          | ''   | '20120405'  
 '350NH/65A'                    | 'SMLF'     | 'EMPTY'  | 'CV+35^0MZ00'(!)           = ''              | ''                 | 'CV+35^0MZ00'              |'L_HCBD101195451G'| 'NA'                           | 'IO'       | 'IND SMD 350NH +-20% 65A(HCBD101195-351G)'      | 'CHIP'         | ''          | ''   | '20120405'  
 '1.0UH/3A'                     | 'SMLF'     | 'IND'    | 'CV-1030TN01'(!)           = ''              | ''                 | 'CV-1030TN01'              | 'L_DFE252012C'                    | '1.0UH/3A'                     | 'DISCRETE' | 'IND CHIP 1.0UH 30% 3A(1239AS-H-1R0N=P2)'       | 'CHIP'         | ''          | ''   | '20120405'  
 '1.0UH/3A'                     | 'SMLF'     | 'EMPTY'  | 'CV-1030TN01'(!)           = ''              | ''                 | 'CV-1030TN01'              | 'L_DFE252012C'                    | 'NA'                           | 'IO'       | 'IND CHIP 1.0UH 30% 3A(1239AS-H-1R0N=P2)'       | 'CHIP'         | ''          | ''   | '20120405'  
 '600/0.5A'                     | 'SMLF'     | 'IND'    | 'CX8AG601003'(!)           = ''              | ''                 | 'CX8AG601003'              |'L0603'| '600/0.5A'                     | 'DISCRETE' | 'EMI FILTER BLM18AG601SN1D(600.0.5A)'           | 'CHIP'         | ''          | ''   | '20120416'  
 '600/0.5A'                     | 'SMLF'     | 'EMPTY'  | 'CX8AG601003'(!)           = ''              | ''                 | 'CX8AG601003'              |'L0603'| 'NA'                           | 'IO'       | 'EMI FILTER BLM18AG601SN1D(600.0.5A)'           | 'CHIP'         | ''          | ''   | '20120416'  
 '1.0UH/1A'                     | 'SMLF'     | 'IND'    | 'CV-1010MZ07'(!)           = ''              | ''                 | 'CV-1010MZ07'              |'L1210'| '1.0UH/1A'                     | 'DISCRETE' | 'IND SMD 1U +-20% 1A(LQH32CN1R0M33L)1210'       | 'CHIP'         | ''          | ''   | '20120419'  
 '1.0UH/1A'                     | 'SMLF'     | 'EMPTY'  | 'CV-1010MZ07'(!)           = ''              | ''                 | 'CV-1010MZ07'              |'L1210'| 'NA'                           | 'IO'       | 'IND SMD 1U +-20% 1A(LQH32CN1R0M33L)1210'       | 'CHIP'         | ''          | ''   | '20120419'  
 '80/5A'                        | 'SMLF'     | 'IND'    | 'CX09U800004'(!)           = 'End of Design' | 'End of Life'      | 'CX09U800004'              |'L0805_EOL'| '80/5A'                        | 'DISCRETE' | 'EMI FILTER TI201209U800(80,5A)'                | 'CHIP'         | ''          | ''   | '20120424'  
 '80/5A'                        | 'SMLF'     | 'EMPTY'  | 'CX09U800004'(!)           = 'End of Design' | 'End of Life'      | 'CX09U800004'              |'L0805_EOL'| 'NA'                           | 'IO'       | 'EMI FILTER TI201209U800(80,5A)'                | 'CHIP'         | ''          | ''   | '20120424'  
 '47/300MA'                     | 'SMLF'     | 'IND'    | 'CX8BA470003'(!)           = 'End of Design' | 'Comp-Approve'     | 'CX8BA470003'              |'L0603'| '47/300MA'                     | 'DISCRETE' | 'EMI FITTER BLM18BA470SN1(47.300MA)'            | 'CHIP'         | ''          | ''   | '20120427'  
 '47/300MA'                     | 'SMLF'     | 'EMPTY'  | 'CX8BA470003'(!)           = 'End of Design' | 'Comp-Approve'     | 'CX8BA470003'              |'L0603'| 'NA'                           | 'IO'       | 'EMI FITTER BLM18BA470SN1(47.300MA)'            | 'CHIP'         | ''          | ''   | '20120427'  
 '0.32U/45A'                    | 'SMLF'     | 'IND'    | 'CV+32^0KZ03'(!)           = 'Non-Preferred' | 'End of Life'      | 'CV+32^0KZ03'              |'L_SIHH1309XA_EOL'| '0.32U/45A'                    | 'DISCRETE' | 'IND SMD 0.32U 10% 45A(SIHH1309-R32K)'          | 'CHIP'         | ''          | ''   | '20120502'  
 '0.32U/45A'                    | 'SMLF'     | 'EMPTY'  | 'CV+32^0KZ03'(!)           = 'Non-Preferred' | 'End of Life'      | 'CV+32^0KZ03'              |'L_SIHH1309XA_EOL'| 'NA'                           | 'IO'       | 'IND SMD 0.32U 10% 45A(SIHH1309-R32K)'          | 'CHIP'         | ''          | ''   | '20120502'  
 '0.1UH/16A'                    | 'SMLF'     | 'IND'    | 'CV+10G0MZ00'(!)           = 'Non-Preferred' | 'End of Life'      | 'CV+10G0MZ00'              |'L_SIFH040406_EOL'| '0.1UH/16A'                    | 'DISCRETE' | 'IND SMD 0.1UH 20%16A SIFH040406-R10M-R30'      | 'CHIP'         | ''          | ''   | '20120502'  
 '0.1UH/16A'                    | 'SMLF'     | 'EMPTY'  | 'CV+10G0MZ00'(!)           = 'Non-Preferred' | 'End of Life'      | 'CV+10G0MZ00'              |'L_SIFH040406_EOL'| 'NA'                           | 'IO'       | 'IND SMD 0.1UH 20%16A SIFH040406-R10M-R30'      | 'CHIP'         | ''          | ''   | '20120502'  
 '1.0U'                         | 'SMLF'     | 'IND'    | 'CV-1015MZ00'(!)           = ''              | ''                 | 'CV-1015MZ00'              |'L_CPL2512T'| '1.0U/1.5A'                    | 'DISCRETE' | 'IND SMD 1.0U +-20% 1.5A(CPL2512T1R0M)'         | 'CHIP'         | ''          | ''   | '20120531'  
 '1.0U'                         | 'SMLF'     | 'EMPTY'  | 'CV-1015MZ00'(!)           = ''              | ''                 | 'CV-1015MZ00'              |'L_CPL2512T'| 'NA'                           | 'IO'       | 'IND SMD 1.0U +-20% 1.5A(CPL2512T1R0M)'         | 'CHIP'         | ''          | ''   | '20120531'  
 '1.5U'                         | 'SMLF'     | 'IND'    | 'CV-1520TZ00'(!)           = ''              | ''                 | 'CV-1520TZ00'              |'L_VLS252012'| '1.5U/2A'                      | 'DISCRETE' | 'IND SMD 1.5U +-30% 2A(VLS252012T-1R5)'         | 'CHIP'         | ''          | ''   | '20120531'  
 '1.5U'                         | 'SMLF'     | 'EMPTY'  | 'CV-1520TZ00'(!)           = ''              | ''                 | 'CV-1520TZ00'              |'L_VLS252012'| 'NA'                           | 'IO'       | 'IND SMD 1.5U +-30% 2A(VLS252012T-1R5)'         | 'CHIP'         | ''          | ''   | '20120531'  
 '220/700MA'                    | 'SMLF'     | 'IND'    | 'CX5EG221008'(!)           = ''              | ''                 | 'CX5EG221008'              |'L0402'| '220/700MA'                    | 'DISCRETE' | 'EMI FILTER BLM15EG221SN1D(220,700MA)'          | 'CHIP'         | ''          | ''   | '20120531'  
 '220/700MA'                    | 'SMLF'     | 'EMPTY'  | 'CX5EG221008'(!)           = ''              | ''                 | 'CX5EG221008'              |'L0402'| 'NA'                           | 'IO'       | 'EMI FILTER BLM15EG221SN1D(220,700MA)'          | 'CHIP'         | ''          | ''   | '20120531'  
 '1.0UH'                        | 'SMLF'     | 'IND'    | 'CV-10^0MZ04'(!)           = ''              | ''                 | 'CV-10^0MZ04'              |'L_HCBD14311'| '1.0UH'                        | 'DISCRETE' | 'IND SMD 1.0UH +-20% 40A(HCBD141311-102)'       | 'CHIP'         | ''          | ''   | '20120605'  
 '1.0UH'                        | 'SMLF'     | 'EMPTY'  | 'CV-10^0MZ04'(!)           = ''              | ''                 | 'CV-10^0MZ04'              |'L_HCBD14311'| 'NA'                           | 'IO'       | 'IND SMD 1.0UH +-20% 40A(HCBD141311-102)'       | 'CHIP'         | ''          | ''   | '20120605'  
 '1.2UH'                        | 'SMLF'     | 'IND'    | 'CV-12X0MZ00'(!)           = ''              | ''                 | 'CV-12X0MZ00'              |'L_HCBD14311'| '1.2UH'                        | 'DISCRETE' | 'IND SMD 1.2UH +-20% 32A(HCBD141311-122)'       | 'CHIP'         | ''          | ''   | '20120605'  
 '1.2UH'                        | 'SMLF'     | 'EMPTY'  | 'CV-12X0MZ00'(!)           = ''              | ''                 | 'CV-12X0MZ00'              |'L_HCBD14311'| 'NA'                           | 'IO'       | 'IND SMD 1.2UH +-20% 32A(HCBD141311-122)'       | 'CHIP'         | ''          | ''   | '20120605'  
 '1.5UH'                        | 'SMLF'     | 'IND'    | 'CV-15Q0MZ00'(!)           = ''              | ''                 | 'CV-15Q0MZ00'              |'L_HCBD14311'| '1.5UH'                        | 'DISCRETE' | 'IND SMD 1.5UH +-20% 25A(HCBD141311-152)'       | 'CHIP'         | ''          | ''   | '20120605'  
 '1.5UH'                        | 'SMLF'     | 'EMPTY'  | 'CV-15Q0MZ00'(!)           = ''              | ''                 | 'CV-15Q0MZ00'              |'L_HCBD14311'| 'NA'                           | 'IO'       | 'IND SMD 1.5UH +-20% 25A(HCBD141311-152)'       | 'CHIP'         | ''          | ''   | '20120605'  
 '0.8UH'                        | 'SMLF'     | 'IND'    | 'CV+80^0MZ00'(!)           = ''              | ''                 | 'CV+80^0MZ00'              |'L_HCBD14311'| '0.8UH'                        | 'DISCRETE' | 'IND SMD 0.8UH +-20% 50A(HCBD141311-801)'       | 'CHIP'         | ''          | ''   | '20120605'  
 '0.8UH'                        | 'SMLF'     | 'EMPTY'  | 'CV+80^0MZ00'(!)           = ''              | ''                 | 'CV+80^0MZ00'              |'L_HCBD14311'| 'NA'                           | 'IO'       | 'IND SMD 0.8UH +-20% 50A(HCBD141311-801)'       | 'CHIP'         | ''          | ''   | '20120605'  
 '10UH'                         | 'SMLF'     | 'IND'    | 'CV01040MZ04'(!)           = ''              | ''                 | 'CV01040MZ04'              |'L_MMD-06CZXA'| '10UH'                         | 'DISCRETE' | 'IND SMD 10UH +-20%,4A(MMD-06CZ-100M-X2Q)'      | 'CHIP'         | ''          | ''   | '20120605'  
 '10UH'                         | 'SMLF'     | 'EMPTY'  | 'CV01040MZ04'(!)           = ''              | ''                 | 'CV01040MZ04'              |'L_MMD-06CZXA'| 'NA'                           | 'IO'       | 'IND SMD 10UH +-20%,4A(MMD-06CZ-100M-X2Q)'      | 'CHIP'         | ''          | ''   | '20120605'  
 '3.3UH'                        | 'SMLF'     | 'IND'    | 'CV-3322MZ09'(!)           = ''              | 'End of Life'      | 'CV-3322MZ09'              |'L_PIDE43-3R3_EOL'| '3.3UH'                        | 'DISCRETE' | 'IND SMD 3.3UH.20%.2.15A(PIDE43-3R3)'           | 'CHIP'         | ''          | ''   | '20120614'  
 '3.3UH'                        | 'SMLF'     | 'EMPTY'  | 'CV-3322MZ09'(!)           = ''              | 'End of Life'      | 'CV-3322MZ09'              |'L_PIDE43-3R3_EOL'| 'NA'                           | 'IO'       | 'IND SMD 3.3UH.20%.2.15A(PIDE43-3R3)'           | 'CHIP'         | ''          | ''   | '20120614'  
 'BLM21PG221SN1D'               | 'SMLF'     | 'IND'    | 'CX1PG221001'(!)           = 'End of Design' | 'Comp-Approve'     | 'CX1PG221001'              |'L0805'| 'BLM21PG221SN1D'               | 'DISCRETE' | 'EMI FILTER BLM21PG221SN1D(220.100M.2A)'        | 'CHIP'         | ''          | ''   | '20120619'  
 'BLM21PG221SN1D'               | 'SMLF'     | 'EMPTY'  | 'CX1PG221001'(!)           = 'End of Design' | 'Comp-Approve'     | 'CX1PG221001'              |'L0805'| 'NA'                           | 'IO'       | 'EMI FILTER BLM21PG221SN1D(220.100M.2A)'        | 'CHIP'         | ''          | ''   | '20120619'  
 '100UH'                        | 'SMLF'     | 'IND'    | 'CV11005MZ00'(!)           = ''              | ''                 | 'CV11005MZ00'              |'L_SIG4018L'| '100UH'                        | 'DISCRETE' | 'IND SMD 100UH 20% 0.45A(SIG4018L-101)'         | 'CHIP'         | ''          | ''   | '20120706'  
 '100UH'                        | 'SMLF'     | 'EMPTY'  | 'CV11005MZ00'(!)           = ''              | ''                 | 'CV11005MZ00'              |'L_SIG4018L'| 'NA'                           | 'IO'       | 'IND SMD 100UH 20% 0.45A(SIG4018L-101)'         | 'CHIP'         | ''          | ''   | '20120706'  
 '8.2NH'                        | 'SMLF'     | 'IND'    | 'CVB8203JN01'(!)           = ''              | ''                 | 'CVB8203JN01'              |'L0402'| '8.2NH'                        | 'DISCRETE' | 'IND CHIP 8.2N(+-5%,0.3A)LQG15HN8N2J02D'        | 'CHIP'         | ''          | ''   | '20120709'  
 '8.2NH'                        | 'SMLF'     | 'EMPTY'  | 'CVB8203JN01'(!)           = ''              | ''                 | 'CVB8203JN01'              |'L0402'| 'NA'                           | 'IO'       | 'IND CHIP 8.2N(+-5%,0.3A)LQG15HN8N2J02D'        | 'CHIP'         | ''          | ''   | '20120709'  
 '2.2NH'                        | 'SMLF'     | 'IND'    | 'CVB2205BN01'(!)           = 'End of Design' | 'Comp-Release Qty' | 'CVB2205BN01'              |'L0201'| '2.2NH'                        | 'DISCRETE' | 'IND CHIP 2.2NH(0.1N,440MA)LQP03TN2N2B00D'      | 'CHIP'         | ''          | ''   | '20120709'  
 '2.2NH'                        | 'SMLF'     | 'EMPTY'  | 'CVB2205BN01'(!)           = 'End of Design' | 'Comp-Release Qty' | 'CVB2205BN01'              |'L0201'| 'NA'                           | 'IO'       | 'IND CHIP 2.2NH(0.1N,440MA)LQP03TN2N2B00D'      | 'CHIP'         | ''          | ''   | '20120709'  
 '8.2NH'                        | 'SMLF'     | 'IND'    | 'CVB8203JN03'(!)           = ''              | ''                 | 'CVB8203JN03'              |'L0402'| '8.2NH'                        | 'DISCRETE' | 'IND CHIP 8.2NH,+-5%,300MA,0402(LQG15HS8)'      | 'CHIP'         | ''          | ''   | '20120709'  
 '8.2NH'                        | 'SMLF'     | 'EMPTY'  | 'CVB8203JN03'(!)           = ''              | ''                 | 'CVB8203JN03'              |'L0402'| 'NA'                           | 'IO'       | 'IND CHIP 8.2NH,+-5%,300MA,0402(LQG15HS8)'      | 'CHIP'         | ''          | ''   | '20120709'  
 '100UH'                        | 'SMLF'     | 'IND'    | 'CV11007MZ00'(!)           = ''              | ''                 | 'CV11007MZ00'              |'L_MNR-4030'| '100UH'                        | 'DISCRETE' | 'IND SMD 100UH +-20% 0.65A(MNR-4030-101M)'      | 'CHIP'         | ''          | ''   | '20120710'  
 '100UH'                        | 'SMLF'     | 'EMPTY'  | 'CV11007MZ00'(!)           = ''              | ''                 | 'CV11007MZ00'              |'L_MNR-4030'| 'NA'                           | 'IO'       | 'IND SMD 100UH +-20% 0.65A(MNR-4030-101M)'      | 'CHIP'         | ''          | ''   | '20120710'  
 '3.3UH'                        | 'SMLF'     | 'IND'    | 'CV-3335MZ01'(!)           = ''              | ''                 | 'CV-3335MZ01'              |'L_MSCDRI6D38'| '3.3UH'                        | 'DISCRETE' | 'IND SMD 3.3U 20% 3.5A MSCDRI-6D38-3R3M'        | 'CHIP'         | ''          | ''   | '20120714'  
 '3.3UH'                        | 'SMLF'     | 'EMPTY'  | 'CV-3335MZ01'(!)           = ''              | ''                 | 'CV-3335MZ01'              |'L_MSCDRI6D38'| 'NA'                           | 'IO'       | 'IND SMD 3.3U 20% 3.5A MSCDRI-6D38-3R3M'        | 'CHIP'         | ''          | ''   | '20120714'  
 '0.47UH'                       | 'SMLF'     | 'IND'    | 'CV+47^0KZ01'(!)           = ''              | ''                 | 'CV+47^0KZ01'              |'L_HCUV138795'| '0.47UH'                       | 'DISCRETE' | 'IND SMD 0.47UH +-10% 41A(HCUV138795-471B'      | 'CHIP'         | ''          | ''   | '20120714'  
 '0.47UH'                       | 'SMLF'     | 'EMPTY'  | 'CV+47^0KZ01'(!)           = ''              | ''                 | 'CV+47^0KZ01'              |'L_HCUV138795'| 'NA'                           | 'IO'       | 'IND SMD 0.47UH +-10% 41A(HCUV138795-471B'      | 'CHIP'         | ''          | ''   | '20120714'  
 '0.27UH'                       | 'SMLF'     | 'IND'    | 'CV+27^0KZ02'(!)           = ''              | ''                 | 'CV+27^0KZ02'              |'L_HCUV138795'| '0.27UH'                       | 'DISCRETE' | 'IND SMD 0.27UH +-10% 72A (HCUV138795-271B)'    | 'CHIP'         | ''          | ''   | '20120714'  
 '0.27UH'                       | 'SMLF'     | 'EMPTY'  | 'CV+27^0KZ02'(!)           = ''              | ''                 | 'CV+27^0KZ02'              |'L_HCUV138795'| 'NA'                           | 'IO'       | 'IND SMD 0.27UH +-10% 72A (HCUV138795-271B)'    | 'CHIP'         | ''          | ''   | '20120714'  
 '0.47UH'                       | 'SMLF'     | 'IND'    | 'CV+47^0KZ00'(!)           = ''              | ''                 | 'CV+47^0KZ00'              |'L_HCB138590'| '0.47UH'                       | 'DISCRETE' | 'IND SMD 0.47UH +-10% 38A (HCB138590-471B)'     | 'CHIP'         | ''          | ''   | '20120714'  
 '0.47UH'                       | 'SMLF'     | 'EMPTY'  | 'CV+47^0KZ00'(!)           = ''              | ''                 | 'CV+47^0KZ00'              |'L_HCB138590'| 'NA'                           | 'IO'       | 'IND SMD 0.47UH +-10% 38A (HCB138590-471B)'     | 'CHIP'         | ''          | ''   | '20120714'  
 '0.27UH'                       | 'SMLF'     | 'IND'    | 'CV+27^0KZ01'(!)           = ''              | ''                 | 'CV+27^0KZ01'              |'L_HCB138590'| '0.27UH'                       | 'DISCRETE' | 'IND SMD 0.27UH +-10% 72A(HCB138590-271B)'      | 'CHIP'         | ''          | ''   | '20120714'  
 '0.27UH'                       | 'SMLF'     | 'EMPTY'  | 'CV+27^0KZ01'(!)           = ''              | ''                 | 'CV+27^0KZ01'              |'L_HCB138590'| 'NA'                           | 'IO'       | 'IND SMD 0.27UH +-10% 72A(HCB138590-271B))'     | 'CHIP'         | ''          | ''   | '20120714'  
 'MPZ2012S101AT(100ohm)'        | 'SMLF'     | 'IND'    | 'CX12S101001'(!)           = 'End of Design' | 'End of Life'      | 'CX12S101001'              |'L0805_EOL'| 'MPZ2012S101AT(100ohm)'        | 'DISCRETE' | 'EMI FIL CHIP MPZ2012S101AT(100.4A)L-F'         | 'CHIP'         | ''          | ''   | '20120714'  
 'MPZ2012S101AT(100ohm)'        | 'SMLF'     | 'EMPTY'  | 'CX12S101001'(!)           = 'End of Design' | 'End of Life'      | 'CX12S101001'              |'L0805_EOL'| 'NA'                           | 'IO'       | 'EMI FIL CHIP MPZ2012S101AT(100.4A)L-F'         | 'CHIP'         | ''          | ''   | '20120714'  
 'BLM18PG471SN1D'               | 'SMLF'     | 'IND'    | 'CX8PG471000'(!)           = ''              | ''                 | 'CX8PG471000'              |'L0603'| 'BLM18PG471SN1D'               | 'DISCRETE' | 'EMI FILTER BLM18PG471SN1D(470.1000MA)'         | 'CHIP'         | ''          | ''   | '20120714'  
 'BLM18PG471SN1D'               | 'SMLF'     | 'EMPTY'  | 'CX8PG471000'(!)           = ''              | ''                 | 'CX8PG471000'              |'L0603'| 'NA'                           | 'IO'       | 'EMI FILTER BLM18PG471SN1D(470.1000MA)'         | 'CHIP'         | ''          | ''   | '20120714'  
 '220NH'                        | 'SMLF'     | 'IND'    | 'CV+20^0KZ00'(!)           = ''              | ''                 | 'CV+20^0KZ00'              |'L_HCB106480N'| '220NH'                        | 'DISCRETE' | 'IND SMD 220NH +-10% 45A(HCB106480N-221A)'      | 'CHIP'         | ''          | ''   | '20120813'  
 '220NH'                        | 'SMLF'     | 'EMPTY'  | 'CV+20^0KZ00'(!)           = ''              | ''                 | 'CV+20^0KZ00'              |'L_HCB106480N'| 'NA'                           | 'IO'       | 'IND SMD 220NH +-10% 45A(HCB106480N-221A)'      | 'CHIP'         | ''          | ''   | '20120813'  
 '320NH'                        | 'SMLF'     | 'IND'    | 'CV+32^0MZ08'(!)           = ''              | ''                 | 'CV+32^0MZ08'              |'L_HCB1190B'| '320NH'                        | 'DISCRETE' | 'IND SMD 320NH.+-20%.42A(HCB1190-321L)'         | 'CHIP'         | ''          | ''   | '20120829'  
 '320NH'                        | 'SMLF'     | 'EMPTY'  | 'CV+32^0MZ08'(!)           = ''              | ''                 | 'CV+32^0MZ08'              |'L_HCB1190B'| 'NA'                           | 'IO'       | 'IND SMD 320NH.+-20%.42A(HCB1190-321L)'         | 'CHIP'         | ''          | ''   | '20120829'  
 '0.1UH'                        | 'SMLF'     | 'IND'    | 'CV+10G0MZ01'(!)           = ''              | ''                 | 'CV+10G0MZ01'              |'L_MSI-400406'| '0.1UH'                        | 'DISCRETE' | 'IND SMD 0.1UH 20% 16A MSI-400406-R10M-E'       | 'CHIP'         | ''          | ''   | '20120831'  
 '0.1UH'                        | 'SMLF'     | 'EMPTY'  | 'CV+10G0MZ01'(!)           = ''              | ''                 | 'CV+10G0MZ01'              |'L_MSI-400406'| 'NA'                           | 'IO'       | 'IND SMD 0.1UH 20% 16A MSI-400406-R10M-E'       | 'CHIP'         | ''          | ''   | '20120831'  
 '75'                           | 'SMLF'     | 'IND'    | 'CXC8BBPH000'(!)           = ''              | ''                 | 'CXC8BBPH000'              |'L3512'| '75'                           | 'DISCRETE' | 'EMI FILTER C8B BPH 853025+TAPING(75,13A)'      | 'CHIP'         | ''          | ''   | '20120904'  
 '75'                           | 'SMLF'     | 'EMPTY'  | 'CXC8BBPH000'(!)           = ''              | ''                 | 'CXC8BBPH000'              |'L3512'| 'NA'                           | 'IO'       | 'EMI FILTER C8B BPH 853025+TAPING(75,13A)'      | 'CHIP'         | ''          | ''   | '20120904'  
 '1.0UH'                        | 'SMLF'     | 'IND'    | 'CV-1003TZ00'(!)           = ''              | ''                 | 'CV-1003TZ00'              |'L0805'| '1.0UH'                        | 'DISCRETE' | 'EMI FILTER C8B BPH 853025+TAPING(75,13A)'      | 'CHIP'         | ''          | ''   | '20120904'  
 '1.0UH'                        | 'SMLF'     | 'EMPTY'  | 'CV-1003TZ00'(!)           = ''              | ''                 | 'CV-1003TZ00'              |'L0805'| 'NA'                           | 'IO'       | 'EMI FILTER C8B BPH 853025+TAPING(75,13A)'      | 'CHIP'         | ''          | ''   | '20120904'  
 '220/2000MA'                   | 'SMLF'     | 'IND'    | 'CX08S221000'(!)           = ''              | ''                 | 'CX08S221000'              |'L0603'| '220/2000MA'                   | 'DISCRETE' | 'EMI FILTER MHC1608S221NBP(220,2000MA)'         | 'CHIP'         | ''          | ''   | '20120905'  
 '220/2000MA'                   | 'SMLF'     | 'EMPTY'  | 'CX08S221000'(!)           = ''              | ''                 | 'CX08S221000'              |'L0603'| 'NA'                           | 'IO'       | 'EMI FILTER MHC1608S221NBP(220,2000MA)'         | 'CHIP'         | ''          | ''   | '20120905'  
 '2.2UH/46A'                    | 'SMLF'     | 'IND'    | 'CV-22^0MZ01'(!)           = 'End of Design' | 'Comp-Approve'     | 'CV-22^0MZ01'              |'L_MPT1365'| '2.2UH/46A'                    | 'DISCRETE' | 'IND SMD 2.2UH +-20% 46A(MPT1365-2R2H1IN)'      | 'CHIP'         | ''          | ''   | '20120910'  
 '2.2UH/46A'                    | 'SMLF'     | 'EMPTY'  | 'CV-22^0MZ01'(!)           = 'End of Design' | 'Comp-Approve'     | 'CV-22^0MZ01'              |'L_MPT1365'| 'NA'                           | 'IO'       | 'IND SMD 2.2UH +-20% 46A(MPT1365-2R2H1IN)'      | 'CHIP'         | ''          | ''   | '20120910'  
 '220/1500MA'                   | 'SMLF'     | 'IND'    | 'CX221T15000'(!)           = ''              | ''                 | 'CX221T15000'              |'L0603'| '220/1500MA'                   | 'DISCRETE' | 'EMI FILTER HCB1608KF-221T15(220,1500MA)'       | 'CHIP'         | ''          | ''   | '20120917'  
 '220/1500MA'                   | 'SMLF'     | 'EMPTY'  | 'CX221T15000'(!)           = ''              | ''                 | 'CX221T15000'              |'L0603'| 'NA'                           | 'IO'       | 'EMI FILTER HCB1608KF-221T15(220,1500MA)'       | 'CHIP'         | ''          | ''   | '20120917'  
 '220/1.4A'                     | 'SMLF'     | 'IND'    | 'CX8PG221003'(!)           = ''              | ''                 | 'CX8PG221003'              |'L0603'| '220/1.4A'                     | 'DISCRETE' | 'EMI FILTER CHIP BLM18PG221SN1D(220,1.4A)'      | 'CHIP'         | ''          | ''   | '20120917'  
 '220/1.4A'                     | 'SMLF'     | 'EMPTY'  | 'CX8PG221003'(!)           = ''              | ''                 | 'CX8PG221003'              |'L0603'| 'NA'                           | 'IO'       | 'EMI FILTER CHIP BLM18PG221SN1D(220,1.4A)'      | 'CHIP'         | ''          | ''   | '20120917'  
 '270NH/55A'                    | 'SMLF'     | 'IND'    | 'CV+27^0KZ03'(!)           = ''              | ''                 | 'CV+27^0KZ03'              |'L_HCUV117595'| '270NH/55A'                    | 'DISCRETE' | 'IND SMD 270NH +-10% 55A(HCUV117595-271B)'      | 'CHIP'         | ''          | ''   | '20120919'  
 '270NH/55A'                    | 'SMLF'     | 'EMPTY'  | 'CV+27^0KZ03'(!)           = ''              | ''                 | 'CV+27^0KZ03'              |'L_HCUV117595'| 'NA'                           | 'IO'       | 'IND SMD 270NH +-10% 55A(HCUV117595-271B)'      | 'CHIP'         | ''          | ''   | '20120919'  
 '4.7UH/10A'                    | 'SMLF'     | 'IND'    | 'CV-4710MZ14'(!)           = ''              | ''                 | 'CV-4710MZ14'              |'L_MMD-10DE'| '4.7UH/10A'                    | 'DISCRETE' | 'IND SMD 4.7UH +-20%10A(MMD-10DE-4R7M-X2Q'      | 'CHIP'         | ''          | ''   | '20120921'  
 '4.7UH/10A'                    | 'SMLF'     | 'EMPTY'  | 'CV-4710MZ14'(!)           = ''              | ''                 | 'CV-4710MZ14'              |'L_MMD-10DE'| 'NA'                           | 'IO'       | 'IND SMD 4.7UH +-20%10A(MMD-10DE-4R7M-X2Q'      | 'CHIP'         | ''          | ''   | '20120921'  
 '3.3UH/6A'                     | 'SMLF'     | 'IND'    | 'CV-3360MZ07'(!)           = ''              | ''                 | 'CV-3360MZ07'              |'L_PCMC063T'| '3.3UH/6A'                     | 'DISCRETE' | 'IND SMD 3.3UH,6A20%(PCMC063T-3R3MN)'           | 'CHIP'         | ''          | ''   | '20120921'  
 '3.3UH/6A'                     | 'SMLF'     | 'EMPTY'  | 'CV-3360MZ07'(!)           = ''              | ''                 | 'CV-3360MZ07'              |'L_PCMC063T'| 'NA'                           | 'IO'       | 'IND SMD 3.3UH,6A20%(PCMC063T-3R3MN)'           | 'CHIP'         | ''          | ''   | '20120921'  
 '2.2UH/12A'                    | 'SMLF'     | 'IND'    | 'CV-22C0MZ04'(!)           = ''              | ''                 | 'CV-22C0MZ04'              |'L_MMD-10DZ'| '2.2UH/12A'                    | 'DISCRETE' | 'IND SMD 2.2UH+-20%12A(MMD-10DZ-2R2M-X2Q)'      | 'CHIP'         | ''          | ''   | '20121004'  
 '2.2UH/12A'                    | 'SMLF'     | 'EMPTY'  | 'CV-22C0MZ04'(!)           = ''              | ''                 | 'CV-22C0MZ04'              |'L_MMD-10DZ'| 'NA'                           | 'IO'       | 'IND SMD 2.2UH+-20%12A(MMD-10DZ-2R2M-X2Q)'      | 'CHIP'         | ''          | ''   | '20121004'  
 '3.3UH/11A'                    | 'SMLF'     | 'IND'    | 'CV-33B0MZ00'(!)           = ''              | ''                 | 'CV-33B0MZ00'              |'L_MMD-10DE'| '3.3UH/11A'                    | 'DISCRETE' | 'IND SMD 3.3UH 11A +-20%(MMD-10DE-3R3M)'        | 'CHIP'         | ''          | ''   | '20121018'  
 '3.3UH/11A'                    | 'SMLF'     | 'EMPTY'  | 'CV-33B0MZ00'(!)           = ''              | ''                 | 'CV-33B0MZ00'              |'L_MMD-10DE'| 'NA'                           | 'IO'       | 'IND SMD 3.3UH 11A +-20%(MMD-10DE-3R3M)'        | 'CHIP'         | ''          | ''   | '20121018'  
 '3.3UH/5A'                     | 'SMLF'     | 'IND'    | 'CV-3350MZ04'(!)           = ''              | ''                 | 'CV-3350MZ04'              |'L_MMD-05CZ-3R3M-M2Q'| '3.3UH/5A'                     | 'DISCRETE' | 'IND SMD 3.3U +-20% 5A(MMD-05CZ-3R3M-M2Q)'      | 'CHIP'         | ''          | ''   | '20121018'  
 '3.3UH/5A'                     | 'SMLF'     | 'EMPTY'  | 'CV-3350MZ04'(!)           = ''              | ''                 | 'CV-3350MZ04'              |'L_MMD-05CZ-3R3M-M2Q'| 'NA'                           | 'IO'       | 'IND SMD 3.3U +-20% 5A(MMD-05CZ-3R3M-M2Q)'      | 'CHIP'         | ''          | ''   | '20121018'  
 '2.2UH/5.5A'                   | 'SMLF'     | 'IND'    | 'CV-2255MZ01'(!)           = ''              | ''                 | 'CV-2255MZ01'              |'L_MMD-05CZ-2R2M-X2Q'| '2.2UH/5.5A'                   | 'DISCRETE' | 'IND SMD 2.2UH 20% 5.5A MMD-05CZ-2R2M-X2Q'      | 'CHIP'         | ''          | ''   | '20121018'  
 '2.2UH/5.5A'                   | 'SMLF'     | 'EMPTY'  | 'CV-2255MZ01'(!)           = ''              | ''                 | 'CV-2255MZ01'              |'L_MMD-05CZ-2R2M-X2Q'| 'NA'                           | 'IO'       | 'IND SMD 2.2UH 20% 5.5A MMD-05CZ-2R2M-X2Q'      | 'CHIP'         | ''          | ''   | '20121018'  
 'BLM21AH601SN1D'               | 'SMLF'     | 'IND'    | 'CX21AH60002'(!)           = 'End of Design' | 'End of Life'      | 'CX21AH60002'              |'L0805_EOL'| 'BLM21AH601SN1D'               | 'DISCRETE' | 'EMI FILTER BLM21AH601SN1D(600@100MHZ)'         | 'CHIP'         | ''          | ''   | '20121024'  
 'BLM21AH601SN1D'               | 'SMLF'     | 'EMPTY'  | 'CX21AH60002'(!)           = 'End of Design' | 'End of Life'      | 'CX21AH60002'              |'L0805_EOL'| 'NA'                           | 'IO'       | 'EMI FILTER BLM21AH601SN1D(600@100MHZ)'         | 'CHIP'         | ''          | ''   | '20121024'  
 '1.5UH/4A'                     | 'SMLF'     | 'IND'    | 'CV-1540MZ02'(!)           = ''              | ''                 | 'CV-1540MZ02'              |'L_MMD-04BZ-1R5M-X2'| '1.5UH/4A'                     | 'DISCRETE' | 'IND SMD 1.5UH 20% 4A MMD-04BZ-1R5M-X2'         | 'CHIP'         | ''          | ''   | '20121030'  
 '1.5UH/4A'                     | 'SMLF'     | 'EMPTY'  | 'CV-1540MZ02'(!)           = ''              | ''                 | 'CV-1540MZ02'              |'L_MMD-04BZ-1R5M-X2'| 'NA'                           | 'IO'       | 'IND SMD 1.5UH 20% 4A MMD-04BZ-1R5M-X2'         | 'CHIP'         | ''          | ''   | '20121030'  
 '220NH/60A'                    | 'SMLF'     | 'IND'    | 'TMP_T2H_KC_1130_1'(!)     = ''              | ''                 | 'TMP_T2H_KC_1130_1'        |'L_HCB147270-221'| '220NH/60A'                    | 'DISCRETE' | 'IND SMD 220NH.+-20%.60A(HCB147270-221)'        | 'CHIP'         | ''          | ''   | '20121030'  
 '220NH/60A'                    | 'SMLF'     | 'EMPTY'  | 'TMP_T2H_KC_1130_1'(!)     = ''              | ''                 | 'TMP_T2H_KC_1130_1'        |'L_HCB147270-221'| 'NA'                           | 'IO'       | 'IND SMD 220NH.+-20%.60A(HCB147270-221)'        | 'CHIP'         | ''          | ''   | '20121030'  
 '220NH/57A'                    | 'SMLF'     | 'IND'    | 'TMP_T2H_KC_1130_2'(!)     = ''              | ''                 | 'TMP_T2H_KC_1130_2'        |'L_HCB147070-221'| '220NH/57A'                    | 'DISCRETE' | 'IND SMD 220NH.+-20%.57A(HCB147070-221)'        | 'CHIP'         | ''          | ''   | '20121030'  
 '220NH/57A'                    | 'SMLF'     | 'EMPTY'  | 'TMP_T2H_KC_1130_2'(!)     = ''              | ''                 | 'TMP_T2H_KC_1130_2'        |'L_HCB147070-221'| 'NA'                           | 'IO'       | 'IND SMD 220NH.+-20%.57A(HCB147070-221)'        | 'CHIP'         | ''          | ''   | '20121030'  
 'BLM21PG300SN1D'               | 'SMLF'     | 'IND'    | 'CX1PG300008'(!)           = ''              | ''                 | 'CX1PG300008'              |'L0805'| 'BLM21PG300SN1D'               | 'DISCRETE' | 'EMI FILTER CHIP BLM21PG300SN1D(30. 3A)'        | 'CHIP'         | ''          | ''   | '20121204'  
 'BLM21PG300SN1D'               | 'SMLF'     | 'EMPTY'  | 'CX1PG300008'(!)           = ''              | ''                 | 'CX1PG300008'              |'L0805'| 'NA'                           | 'IO'       | 'EMI FILTER CHIP BLM21PG300SN1D(30. 3A)'        | 'CHIP'         | ''          | ''   | '20121204'  
 '0.24UH/28A'                   | 'SMLF'     | 'IND'    | 'CV+24T0MZ00'(!)           = ''              | ''                 | 'CV+24T0MZ00'              |'L_MMD-06CZ'| '0.24UH/28A'                   | 'DISCRETE' | 'IND SMD0.24UH+-20%28A(MMD-06CZNR24MEM1Q)'      | 'CHIP'         | ''          | ''   | '20121212'  
 '0.24UH/28A'                   | 'SMLF'     | 'EMPTY'  | 'CV+24T0MZ00'(!)           = ''              | ''                 | 'CV+24T0MZ00'              |'L_MMD-06CZ'| 'NA'                           | 'IO'       | 'IND SMD0.24UH+-20%28A(MMD-06CZNR24MEM1Q)'      | 'CHIP'         | ''          | ''   | '20121212'  
 '0.22UH/30A'                   | 'SMLF'     | 'IND'    | 'CV+22V0MZ01'(!)           = ''              | ''                 | 'CV+22V0MZ01'              |'L_MMD-06DZ'| '0.22UH/30A'                   | 'DISCRETE' | 'IND SMD 0.22UH 20%30A(MMD-06DZ-R22M-X2Q)'      | 'CHIP'         | ''          | ''   | '20121212'  
 '0.22UH/30A'                   | 'SMLF'     | 'EMPTY'  | 'CV+22V0MZ01'(!)           = ''              | ''                 | 'CV+22V0MZ01'              |'L_MMD-06DZ'| 'NA'                           | 'IO'       | 'IND SMD 0.22UH 20%30A(MMD-06DZ-R22M-X2Q)'      | 'CHIP'         | ''          | ''   | '20121212'  
 '4.7UH/3.5A'                   | 'SMLF'     | 'IND'    | 'CV-4735MZ00'(!)           = ''              | ''                 | 'CV-4735MZ00'              |'L_MMD-05AH'| '4.7UH/3.5A'                   | 'DISCRETE' | 'IND SMD 4.7U,3.5A,20%(MMD-05AH-4R7M-X2Q)'      | 'CHIP'         | ''          | ''   | '20121212'  
 '4.7UH/3.5A'                   | 'SMLF'     | 'EMPTY'  | 'CV-4735MZ00'(!)           = ''              | ''                 | 'CV-4735MZ00'              |'L_MMD-05AH'| 'NA'                           | 'IO'       | 'IND SMD 4.7U,3.5A,20%(MMD-05AH-4R7M-X2Q)'      | 'CHIP'         | ''          | ''   | '20121212'  
 '10UH/2.5A'                    | 'SMLF'     | 'IND'    | 'CV01025MZ02'(!)           = ''              | ''                 | 'CV01025MZ02'              |'L_MMD-05AH'| '10UH/2.5A'                    | 'DISCRETE' | 'IND SMD 10UH+-20% 2.5A MMD-05AH-100M-X2Q'      | 'CHIP'         | ''          | ''   | '20121212'  
 '10UH/2.5A'                    | 'SMLF'     | 'EMPTY'  | 'CV01025MZ02'(!)           = ''              | ''                 | 'CV01025MZ02'              |'L_MMD-05AH'| 'NA'                           | 'IO'       | 'IND SMD 10UH+-20% 2.5A MMD-05AH-100M-X2Q'      | 'CHIP'         | ''          | ''   | '20121212'  
 'MPZ1608S300AT/5A'             | 'SMLF'     | 'IND'    | 'CX08S300000'(!)           = 'End of Design' | 'Comp-Approve'     | 'CX08S300000'              |'L0603'| 'MPZ1608S300AT/5A'             | 'DISCRETE' | 'EMI FILTER CHIP MPZ1608S300AT(30,5A)'          | 'CHIP'         | ''          | ''   | '20121214'  
 'MPZ1608S300AT/5A'             | 'SMLF'     | 'EMPTY'  | 'CX08S300000'(!)           = 'End of Design' | 'Comp-Approve'     | 'CX08S300000'              |'L0603'| 'NA'                           | 'IO'       | 'EMI FILTER CHIP MPZ1608S300AT(30,5A)'          | 'CHIP'         | ''          | ''   | '20121214'  
 'MPZ2012S221AT/3A'             | 'SMLF'     | 'IND'    | 'CX12S221001'(!)           = 'End of Design' | 'End of Life'      | 'CX12S221001'              |'L0805_EOL'| 'MPZ2012S221AT/3A'             | 'DISCRETE' | 'EMI FILTER CHIP MPZ2012S221AT(220,3A)'         | 'CHIP'         | ''          | ''   | '20121214'  
 'MPZ2012S221AT/3A'             | 'SMLF'     | 'EMPTY'  | 'CX12S221001'(!)           = 'End of Design' | 'End of Life'      | 'CX12S221001'              |'L0805_EOL'| 'NA'                           | 'IO'       | 'EMI FILTER CHIP MPZ2012S221AT(220,3A)'         | 'CHIP'         | ''          | ''   | '20121214'  
 'BLM15AX601SN1D/420MA'         | 'SMLF'     | 'IND'    | 'CX5AX601000'(!)           = ''              | ''                 | 'CX5AX601000'              |'L0402'| 'BLM15AX601SN1D/420MA'         | 'DISCRETE' | 'EMI FILTER BLM15AX601SN1D(600,420MA)'          | 'CHIP'         | ''          | ''   | '20121222'  
 'BLM15AX601SN1D/420MA'         | 'SMLF'     | 'EMPTY'  | 'CX5AX601000'(!)           = ''              | ''                 | 'CX5AX601000'              |'L0402'| 'NA'                           | 'IO'       | 'EMI FILTER BLM15AX601SN1D(600,420MA)'          | 'CHIP'         | ''          | ''   | '20121222'  
 '0.36UH/45A'                   | 'SMLF'     | 'IND'    | 'CV+36^0KZ00'(!)           = ''              | ''                 | 'CV+36^0KZ00'              |'L_HCUV117595'| '0.36UH/45A'                   | 'DISCRETE' | 'IND SMD 0.36UH +-10% 45A(HCUV117595-361B'      | 'CHIP'         | ''          | ''   | '20121227'  
 '0.36UH/45A'                   | 'SMLF'     | 'EMPTY'  | 'CV+36^0KZ00'(!)           = ''              | ''                 | 'CV+36^0KZ00'              |'L_HCUV117595'| 'NA'                           | 'IO'       | 'IND SMD 0.36UH +-10% 45A(HCUV117595-361B'      | 'CHIP'         | ''          | ''   | '20121227'  
 '0.47UH/45A'                   | 'SMLF'     | 'IND'    | 'CV+47^0KZ02'(!)           = ''              | ''                 | 'CV+47^0KZ02'              |'L_HCUV117595'| '0.47UH/45A'                   | 'DISCRETE' | 'IND SMD 0.47UH +-10% 45A(HCUV117595-471B'      | 'CHIP'         | ''          | ''   | '20121227'  
 '0.47UH/45A'                   | 'SMLF'     | 'EMPTY'  | 'CV+47^0KZ02'(!)           = ''              | ''                 | 'CV+47^0KZ02'              |'L_HCUV117595'| 'NA'                           | 'IO'       | 'IND SMD 0.47UH +-10% 45A(HCUV117595-471B'      | 'CHIP'         | ''          | ''   | '20121227'  
 '2.2UH/5.5A'                   | 'SMLF'     | 'IND'    | 'CV-2255MZ00'(!)           = ''              | ''                 | 'CV-2255MZ00'              |'L_MMD-05CZ-2R2M-X1Q'| '2.2UH/5.5A'                   | 'DISCRETE' | 'IND SMD 2.2UH 20% 5.5A MMD-05CZ-2R2M-X1Q'      | 'CHIP'         | ''          | ''   | '20130103'  
 '2.2UH/5.5A'                   | 'SMLF'     | 'EMPTY'  | 'CV-2255MZ00'(!)           = ''              | ''                 | 'CV-2255MZ00'              |'L_MMD-05CZ-2R2M-X1Q'| 'NA'                           | 'IO'       | 'IND SMD 2.2UH 20% 5.5A MMD-05CZ-2R2M-X1Q'      | 'CHIP'         | ''          | ''   | '20130103'  
 'HCB1608KF-601T10/1A'          | 'SMLF'     | 'IND'    | 'CX601T10000'(!)           = ''              | ''                 | 'CX601T10000'              |'L0603'| 'HCB1608KF-601T10/1A'          | 'DISCRETE' | 'EMI FILTER CHIP HCB1608KF-601T10(600,1A)'      | 'CHIP'         | ''          | ''   | '20130103'  
 'HCB1608KF-601T10/1A'          | 'SMLF'     | 'EMPTY'  | 'CX601T10000'(!)           = ''              | ''                 | 'CX601T10000'              |'L0603'| 'NA'                           | 'IO'       | 'EMI FILTER CHIP HCB1608KF-601T10(600,1A)'      | 'CHIP'         | ''          | ''   | '20130103'  
 '220NH/45A'                    | 'SMLF'     | 'IND'    | 'CV+22^0EZ00'(!)           = ''              | ''                 | 'CV+22^0EZ00'              |'L_HCUV117595'| '220NH/45A'                    | 'DISCRETE' | 'IND SMD 220NH +-15% 45A(HCUV117595-221)'       | 'CHIP'         | ''          | ''   | '20130114'  
 '220NH/45A'                    | 'SMLF'     | 'EMPTY'  | 'CV+22^0EZ00'(!)           = ''              | ''                 | 'CV+22^0EZ00'              |'L_HCUV117595'| 'NA'                           | 'IO'       | 'IND SMD 220NH +-15% 45A(HCUV117595-221)'       | 'CHIP'         | ''          | ''   | '20130114'  
 '10UH/2.5A'                    | 'SMLF'     | 'IND'    | 'CV01025MZ03'(!)           = ''              | ''                 | 'CV01025MZ03'              |'L_MMD-05CZ-3R3M-M2Q'| '10UH/2.5A'                    | 'DISCRETE' | 'IND SMD 10UH 20% 2.5A MMD-05CZ-100M-V1Q'       | 'CHIP'         | ''          | ''   | '20130115'  
 '10UH/2.5A'                    | 'SMLF'     | 'EMPTY'  | 'CV01025MZ03'(!)           = ''              | ''                 | 'CV01025MZ03'              |'L_MMD-05CZ-3R3M-M2Q'| 'NA'                           | 'IO'       | 'IND SMD 10UH 20% 2.5A MMD-05CZ-100M-V1Q'       | 'CHIP'         | ''          | ''   | '20130115'  
 '1.0UH/9.2A'                   | 'SMLF'     | 'IND'    | 'CV-1092MZ00'(!)           = ''              | ''                 | 'CV-1092MZ00'              |'L_MMD-05CZ-3R3M-M2Q'| '1.0UH/9.2A'                   | 'DISCRETE' | 'IND SMD 1.0UH 20% 9.2A MMD-05CZ-1R0M-V1Q'      | 'CHIP'         | ''          | ''   | '20130115'  
 '1.0UH/9.2A'                   | 'SMLF'     | 'EMPTY'  | 'CV-1092MZ00'(!)           = ''              | ''                 | 'CV-1092MZ00'              |'L_MMD-05CZ-3R3M-M2Q'| 'NA'                           | 'IO'       | 'IND SMD 1.0UH 20% 9.2A MMD-05CZ-1R0M-V1Q'      | 'CHIP'         | ''          | ''   | '20130115'  
 '0.47UH/12.2A'                 | 'SMLF'     | 'IND'    | 'CV+47C2MZ00'(!)           = ''              | ''                 | 'CV+47C2MZ00'              |'L_MMD-05CZ-3R3M-M2Q'| '0.47UH/12.2A'                 | 'DISCRETE' | 'IND SMD 0.47UH 20% 12.2A MMD-05CZ-R47M-V'      | 'CHIP'         | ''          | ''   | '20130115'  
 '0.47UH/12.2A'                 | 'SMLF'     | 'EMPTY'  | 'CV+47C2MZ00'(!)           = ''              | ''                 | 'CV+47C2MZ00'              |'L_MMD-05CZ-3R3M-M2Q'| 'NA'                           | 'IO'       | 'IND SMD 0.47UH 20% 12.2A MMD-05CZ-R47M-V'      | 'CHIP'         | ''          | ''   | '20130115'  
 '1UH/20A'                      | 'SMLF'     | 'IND'    | 'CV-10K0MZ03'(!)           = ''              | ''                 | 'CV-10K0MZ03'              |'L_PB103E'| '1UH/20A'                      | 'DISCRETE' | 'IND SMD 1UH(20%,20A)PCMB103E-1R0MS'            | 'CHIP'         | ''          | ''   | '20130123'  
 '1UH/20A'                      | 'SMLF'     | 'EMPTY'  | 'CV-10K0MZ03'(!)           = ''              | ''                 | 'CV-10K0MZ03'              |'L_PB103E'| 'NA'                           | 'IO'       | 'IND SMD 1UH(20%,20A)PCMB103E-1R0MS'            | 'CHIP'         | ''          | ''   | '20130123'  
 '0.36UH/55A'                   | 'SMLF'     | 'IND'    | 'CV+36^0KZ01'(!)           = ''              | ''                 | 'CV+36^0KZ01'              |'L_THMPF2509'| '0.36UH/55A'                   | 'DISCRETE' | 'IND SMD 0.36UH +-10% 55A(HCUV138795-361B'      | 'CHIP'         | ''          | ''   | '20130220'  
 '0.36UH/55A'                   | 'SMLF'     | 'EMPTY'  | 'CV+36^0KZ01'(!)           = ''              | ''                 | 'CV+36^0KZ01'              |'L_THMPF2509'| 'NA'                           | 'IO'       | 'IND SMD 0.36UH +-10% 55A(HCUV138795-361B'      | 'CHIP'         | ''          | ''   | '20130220'  
 '1UH/13A'                      | 'SMLF'     | 'IND'    | 'CV-10D0MZ08'(!)           = ''              | ''                 | 'CV-10D0MZ08'              |'L_PCMB065T'| '1UH/13A'                      | 'DISCRETE' | 'IND SMD 1UH +-20% 13A(PCMB065T-1R0MS)'         | 'CHIP'         | ''          | ''   | '20130226'  
 '1UH/13A'                      | 'SMLF'     | 'EMPTY'  | 'CV-10D0MZ08'(!)           = ''              | ''                 | 'CV-10D0MZ08'              |'L_PCMB065T'| 'NA'                           | 'IO'       | 'IND SMD 1UH +-20% 13A(PCMB065T-1R0MS)'         | 'CHIP'         | ''          | ''   | '20130226'  
 '270NH/62.5A'                  | 'SMLF'     | 'IND'    | 'TMP_TUIJ_KC_0307_1'(!)    = ''              | ''                 | 'TMP_TUIJ_KC_0307_1'       |'L_HCB149070'| '270NH/62.5A'                  | 'DISCRETE' | 'IND SMD 270NH.+-15%.62.5A(HCB149070-271)'      | 'CHIP'         | ''          | ''   | '20130307'  
 '270NH/62.5A'                  | 'SMLF'     | 'EMPTY'  | 'TMP_TUIJ_KC_0307_1'(!)    = ''              | ''                 | 'TMP_TUIJ_KC_0307_1'       |'L_HCB149070'| 'NA'                           | 'IO'       | 'IND SMD 270NH.+-15%.62.5A(HCB149070-271)'      | 'CHIP'         | ''          | ''   | '20130307'  
 '270NH/55A'                    | 'SMLF'     | 'IND'    | 'TMP_TUIJ_KC_0314_1'(!)    = ''              | ''                 | 'TMP_TUIJ_KC_0314_1'       |'L_HCUV147570'| '270NH/55A'                    | 'DISCRETE' | 'IND SMD 270NH.+-10%.55A(HCUV147570-271)'       | 'CHIP'         | ''          | ''   | '20130314'  
 '270NH/55A'                    | 'SMLF'     | 'EMPTY'  | 'TMP_TUIJ_KC_0314_1'(!)    = ''              | ''                 | 'TMP_TUIJ_KC_0314_1'       |'L_HCUV147570'| 'NA'                           | 'IO'       | 'IND SMD 270NH.+-10%.55A(HCUV147570-271)'       | 'CHIP'         | ''          | ''   | '20130314'  
 '0.32UH/43A'                   | 'SMLF'     | 'IND'    | 'CV+32^0MZ09'(!)           = ''              | ''                 | 'CV+32^0MZ09'              |'L_HCB141390'| '0.32UF/43A'                   | 'DISCRETE' | 'IND SMD 0.32U 20% 43A(HCB141390-321-F)'        | 'CHIP'         | ''          | ''   | '20130319'  
 '0.32UH/43A'                   | 'SMLF'     | 'EMPTY'  | 'CV+32^0MZ09'(!)           = ''              | ''                 | 'CV+32^0MZ09'              |'L_HCB141390'| 'NA'                           | 'IO'       | 'IND SMD 0.32U 20% 43A(HCB141390-321-F)'        | 'CHIP'         | ''          | ''   | '20130319'  
 '0.1UH/40A'                    | 'SMLF'     | 'IND'    | 'CV+10^0MZ08'(!)           = 'Non-Preferred' | 'End of Life'      | 'CV+10^0MZ08'              |'L_L30909-7_EOL'| '0.1UH/40A'                    | 'DISCRETE' | 'IND SMD 0.1UH +-20% 40A(L30909-7)'             | 'CHIP'         | ''          | ''   | '20130327'  
 '0.1UH/40A'                    | 'SMLF'     | 'EMPTY'  | 'CV+10^0MZ08'(!)           = 'Non-Preferred' | 'End of Life'      | 'CV+10^0MZ08'              |'L_L30909-7_EOL'| 'NA'                           | 'IO'       | 'IND SMD 0.1UH +-20% 40A(L30909-7)'             | 'CHIP'         | ''          | ''   | '20130327'  
 '270NH/55A'                    | 'SMLF'     | 'IND'    | 'CV+27^0KZ05'(!)           = ''              | ''                 | 'CV+27^0KZ05'              |'L_HCUV147570'| '270NH/55A'                    | 'DISCRETE' | 'IND SMD 270NH +-10% 55A(HCUV147570-271)'       | 'CHIP'         | ''          | ''   | '20130403'  
 '270NH/55A'                    | 'SMLF'     | 'EMPTY'  | 'CV+27^0KZ05'(!)           = ''              | ''                 | 'CV+27^0KZ05'              |'L_HCUV147570'| 'NA'                           | 'IO'       | 'IND SMD 270NH +-10% 55A(HCUV147570-271)'       | 'CHIP'         | ''          | ''   | '20130403'  
 '270NH/0.55A'                  | 'SMLF'     | 'IND'    | 'CV+27^0KZ06'(!)           = ''              | ''                 | 'CV+27^0KZ06'              |'L_HCUV148070'| '270NH/0.55A'                  | 'DISCRETE' | 'IND SMD 270NH.+-10%.55A(HCUV148070-271)'       | 'CHIP'         | ''          | ''   | '20130410'  
 '270NH/0.55A'                  | 'SMLF'     | 'EMPTY'  | 'CV+27^0KZ06'(!)           = ''              | ''                 | 'CV+27^0KZ06'              |'L_HCUV148070'| 'NA'                           | 'IO'       | 'IND SMD 270NH.+-10%.55A(HCUV148070-271)'       | 'CHIP'         | ''          | ''   | '20130410'  
 'BLM15PX600SN1D/2.5A'          | 'SMLF'     | 'IND'    | 'CX5PX600000'(!)           = ''              | ''                 | 'CX5PX600000'              |'L0402'| 'BLM15PX600SN1D/2.5A'          | 'DISCRETE' | 'EMI FILTER CHIP BLM15PX600SN1D(60, 2.5A)'      | 'CHIP'         | ''          | ''   | '20130422'  
 'BLM15PX600SN1D/2.5A'          | 'SMLF'     | 'EMPTY'  | 'CX5PX600000'(!)           = ''              | ''                 | 'CX5PX600000'              |'L0402'| 'NA'                           | 'IO'       | 'EMI FILTER CHIP BLM15PX600SN1D(60, 2.5A)'      | 'CHIP'         | ''          | ''   | '20130422'  
 '0.1UH/30A'                    | 'SMLF'     | 'IND'    | 'CV+10V0MZ00'(!)           = 'Non-Preferred' | 'End of Life'      | 'CV+10V0MZ00'              |'L_L30909-6_EOL'| '0.1UH/30A'                    | 'DISCRETE' | 'IND SMD 0.1UH +-20% 30A(L30909-6)'             | 'CHIP'         | ''          | ''   | '20130425'  
 '0.1UH/30A'                    | 'SMLF'     | 'EMPTY'  | 'CV+10V0MZ00'(!)           = 'Non-Preferred' | 'End of Life'      | 'CV+10V0MZ00'              |'L_L30909-6_EOL'| 'NA'                           | 'IO'       | 'IND SMD 0.1UH +-20% 30A(L30909-6)'             | 'CHIP'         | ''          | ''   | '20130425'  
 'BLM18SG331TN1D/1.5A'          | 'SMLF'     | 'IND'    | 'CX8SG331000'(!)           = 'End of Design' | 'Comp-Approve'     | 'CX8SG331000'              |'L0603'| 'BLM18SG331TN1D/1.5A'          | 'DISCRETE' | 'EMI FILTER BLM18SG331TN1D(330,1.5A)'           | 'CHIP'         | ''          | ''   | '20130520'  
 'BLM18SG331TN1D/1.5A'          | 'SMLF'     | 'EMPTY'  | 'CX8SG331000'(!)           = 'End of Design' | 'Comp-Approve'     | 'CX8SG331000'              |'L0603'| 'NA'                           | 'IO'       | 'EMI FILTER BLM18SG331TN1D(330,1.5A)'           | 'CHIP'         | ''          | ''   | '20130520'  
 '0.22UH/87A'                   | 'SMLF'     | 'IND'    | 'CV+22^0KZ06'(!)           = ''              | ''                 | 'CV+22^0KZ06'              |'L_HCB138795-221B'| '0.22UH/87A'                   | 'DISCRETE' | 'IND SMD 0.22UH +-10% 87A(HCUV138795-221B'      | 'CHIP'         | ''          | ''   | '20130523'  
 '0.22UH/87A'                   | 'SMLF'     | 'EMPTY'  | 'CV+22^0KZ06'(!)           = ''              | ''                 | 'CV+22^0KZ06'              |'L_HCB138795-221B'| 'NA'                           | 'IO'       | 'IND SMD 0.22UH +-10% 87A(HCUV138795-221B'      | 'CHIP'         | ''          | ''   | '20130523'  
 '0.27UH/70A'                   | 'SMLF'     | 'IND'    | 'CV+27^0KZ08'(!)           = ''              | ''                 | 'CV+27^0KZ08'              |'L_HCUV138795L-271'| '0.27UH/70A'                   | 'DISCRETE' | 'IND SMD 0.27UH +-10% 70A(HCUV138795L-271'      | 'CHIP'         | ''          | ''   | '20130523'  
 '0.27UH/70A'                   | 'SMLF'     | 'EMPTY'  | 'CV+27^0KZ08'(!)           = ''              | ''                 | 'CV+27^0KZ08'              |'L_HCUV138795L-271'| 'NA'                           | 'IO'       | 'IND SMD 0.27UH +-10% 70A(HCUV138795L-271'      | 'CHIP'         | ''          | ''   | '20130523'  
 '1000UH/0.1A'                  | 'SMLF'     | 'IND'    | 'CV21001MZ01'(!)           = ''              | ''                 | 'CV21001MZ01'              |'L_MLPS-4018'| '1000UH/0.1A'                  | 'DISCRETE' | 'IND SMD 1000UH 20% 0.1A(MLPS-4018-102M)'       | 'CHIP'         | ''          | ''   | '20130610'  
 '1000UH/0.1A'                  | 'SMLF'     | 'EMPTY'  | 'CV21001MZ01'(!)           = ''              | ''                 | 'CV21001MZ01'              |'L_MLPS-4018'| 'NA'                           | 'IO'       | 'IND SMD 1000UH 20% 0.1A(MLPS-4018-102M)'       | 'CHIP'         | ''          | ''   | '20130610'  
 '2.2UH/40A'                    | 'SMLF'     | 'IND'    | 'CV-22^0MZ02'(!)           = ''              | ''                 | 'CV-22^0MZ02'              |'L_MMD12FD'| '2.2UH/40A'                    | 'DISCRETE' | 'IND SMD 2.2UH 20% 40A(MMD-12FD-2R2M-V1Q)'      | 'CHIP'         | ''          | ''   | '20130614'  
 '2.2UH/40A'                    | 'SMLF'     | 'EMPTY'  | 'CV-22^0MZ02'(!)           = ''              | ''                 | 'CV-22^0MZ02'              |'L_MMD12FD'| 'NA'                           | 'IO'       | 'IND SMD 2.2UH 20% 40A(MMD-12FD-2R2M-V1Q)'      | 'CHIP'         | ''          | ''   | '20130614'  
 '3.3UH/10A'                    | 'SMLF'     | 'IND'    | 'CV-33A0MZ02'(!)           = ''              | ''                 | 'CV-33A0MZ02'              |'L_PCMB104TXB'| '3.3UH/10A'                    | 'DISCRETE' | 'IND SMD 3.3UH+-20%10A(PCMB104T-3R3MS)'         | 'CHIP'         | ''          | ''   | '20130619'  
 '3.3UH/10A'                    | 'SMLF'     | 'EMPTY'  | 'CV-33A0MZ02'(!)           = ''              | ''                 | 'CV-33A0MZ02'              |'L_PCMB104TXB'| 'NA'                           | 'IO'       | 'IND SMD 3.3UH+-20%10A(PCMB104T-3R3MS)'         | 'CHIP'         | ''          | ''   | '20130619'  
 'BLM18BB470/500MA'             | 'SMLF'     | 'IND'    | 'CX8BB470007'(!)           = ''              | ''                 | 'CX8BB470007'              |'L0603'| 'BLM18BB470/500MA'             | 'DISCRETE' | 'EMI FILTER CHIP BLM18BB470(47.500MA)'          | 'CHIP'         | ''          | ''   | '20130704'  
 'BLM18BB470/500MA'             | 'SMLF'     | 'EMPTY'  | 'CX8BB470007'(!)           = ''              | ''                 | 'CX8BB470007'              |'L0603'| 'NA'                           | 'IO'       | 'EMI FILTER CHIP BLM18BB470(47.500MA)'          | 'CHIP'         | ''          | ''   | '20130704'  
 '1.0UH/2.22A'                  | 'SMLF'     | 'IND'    | 'CV-1023TZ02'(!)           = ''              | ''                 | 'CV-1023TZ02'              |'L_VLF302510MT-1R0N'| '1.0UH/2.22A'                  | 'DISCRETE' | 'IND SMD 1.0U 30% 2.22A(VLF302510MT-1R0N)'      | 'CHIP'         | ''          | ''   | '20130715'  
 '1.0UH/2.22A'                  | 'SMLF'     | 'EMPTY'  | 'CV-1023TZ02'(!)           = ''              | ''                 | 'CV-1023TZ02'              |'L_VLF302510MT-1R0N'| 'NA'                           | 'IO'       | 'IND SMD 1.0U 30% 2.22A(VLF302510MT-1R0N)'      | 'CHIP'         | ''          | ''   | '20130715'  
 '1.0UH/50A'                    | 'SMLF'     | 'IND'    | 'CV-10^0KZ00'(!)           = ''              | ''                 | 'CV-10^0KZ00'              |'L_HCBD141312'| '1.0UH/50A'                    | 'DISCRETE' | 'IND SMD 1.0UH +-10% 50A(HCBD141312-102)'       | 'CHIP'         | ''          | ''   | '20130726'  
 '1.0UH/50A'                    | 'SMLF'     | 'EMPTY'  | 'CV-10^0KZ00'(!)           = ''              | ''                 | 'CV-10^0KZ00'              |'L_HCBD141312'| 'NA'                           | 'IO'       | 'IND SMD 1.0UH +-10% 50A(HCBD141312-102)'       | 'CHIP'         | ''          | ''   | '20130726'  
 '1.2UH/43A'                    | 'SMLF'     | 'IND'    | 'CV-12^0KZ00'(!)           = ''              | ''                 | 'CV-12^0KZ00'              |'L_HCBD141312'| '1.2UH/43A'                    | 'DISCRETE' | 'IND SMD 1.2UH +-10% 43A(HCBD141312-122)'       | 'CHIP'         | ''          | ''   | '20130726'  
 '1.2UH/43A'                    | 'SMLF'     | 'EMPTY'  | 'CV-12^0KZ00'(!)           = ''              | ''                 | 'CV-12^0KZ00'              |'L_HCBD141312'| 'NA'                           | 'IO'       | 'IND SMD 1.2UH +-10% 43A(HCBD141312-122)'       | 'CHIP'         | ''          | ''   | '20130726'  
 '1.5UH/34A'                    | 'SMLF'     | 'IND'    | 'CV-15Z0KZ00'(!)           = ''              | ''                 | 'CV-15Z0KZ00'              |'L_HCBD141312'| '1.5UH/34A'                    | 'DISCRETE' | 'IND SMD 1.5UH +-10% 34A(HCBD141312-152)'       | 'CHIP'         | ''          | ''   | '20130726'  
 '1.5UH/34A'                    | 'SMLF'     | 'EMPTY'  | 'CV-15Z0KZ00'(!)           = ''              | ''                 | 'CV-15Z0KZ00'              |'L_HCBD141312'| 'NA'                           | 'IO'       | 'IND SMD 1.5UH +-10% 34A(HCBD141312-152)'       | 'CHIP'         | ''          | ''   | '20130726'  
 '2.2UH/24A'                    | 'SMLF'     | 'IND'    | 'CV-22P0KZ00'(!)           = ''              | ''                 | 'CV-22P0KZ00'              |'L_HCBD141312'| '2.2UH/24A'                    | 'DISCRETE' | 'IND SMD 2.2UH +-10% 24A(HCBD141312-222)'       | 'CHIP'         | ''          | ''   | '20130726'  
 '2.2UH/24A'                    | 'SMLF'     | 'EMPTY'  | 'CV-22P0KZ00'(!)           = ''              | ''                 | 'CV-22P0KZ00'              |'L_HCBD141312'| 'NA'                           | 'IO'       | 'IND SMD 2.2UH +-10% 24A(HCBD141312-222)'       | 'CHIP'         | ''          | ''   | '20130726'  
 'MPZ2012S601AT/2A'             | 'SMLF'     | 'IND'    | 'CX12S601000'(!)           = 'End of Design' | 'Comp-Approve'     | 'CX12S601000'              |'L0805'| 'MPZ2012S601AT/2A'             | 'DISCRETE' | 'EMI FIL CHIP MPZ2012S601AT(600,2A)'            | 'CHIP'         | ''          | ''   | '20130731'  
 'MPZ2012S601AT/2A'             | 'SMLF'     | 'EMPTY'  | 'CX12S601000'(!)           = 'End of Design' | 'Comp-Approve'     | 'CX12S601000'              |'L0805'| 'NA'                           | 'IO'       | 'EMI FIL CHIP MPZ2012S601AT(600,2A)'            | 'CHIP'         | ''          | ''   | '20130731'  
 '1.5UH/27A'                    | 'SMLF'     | 'IND'    | 'CV-15S0MZ00'(!)           = ''              | ''                 | 'CV-15S0MZ00'              |'L_MMD12FD'| '1.5UH/27A'                    | 'DISCRETE' | 'IND SMD 1.5UH 20% 27A MMD-12FD-1R5M-V1Q'       | 'CHIP'         | ''          | ''   | '20130805'  
 '1.5UH/27A'                    | 'SMLF'     | 'EMPTY'  | 'CV-15S0MZ00'(!)           = ''              | ''                 | 'CV-15S0MZ00'              |'L_MMD12FD'| 'NA'                           | 'IO'       | 'IND SMD 1.5UH 20% 27A MMD-12FD-1R5M-V1Q'       | 'CHIP'         | ''          | ''   | '20130805'  
 '3.3UH/18A'                    | 'SMLF'     | 'IND'    | 'CV-33I0MZ00'(!)           = ''              | ''                 | 'CV-33I0MZ00'              |'L_MMD12FD'| '3.3UH/18A'                    | 'DISCRETE' | 'IND SMD 3.3UH 20% 18A MMD-12FD-3R3M-V1Q'       | 'CHIP'         | ''          | ''   | '20130805'  
 '3.3UH/18A'                    | 'SMLF'     | 'EMPTY'  | 'CV-33I0MZ00'(!)           = ''              | ''                 | 'CV-33I0MZ00'              |'L_MMD12FD'| 'NA'                           | 'IO'       | 'IND SMD 3.3UH 20% 18A MMD-12FD-3R3M-V1Q'       | 'CHIP'         | ''          | ''   | '20130805'  
 '4.7UH/13.5A'                  | 'SMLF'     | 'IND'    | 'CV-47D5MZ00'(!)           = ''              | ''                 | 'CV-47D5MZ00'              |'L_MMD12FD'| '4.7UH/13.5A'                  | 'DISCRETE' | 'IND SMD 4.7UH20% 13.5A MMD-12FD-4R7M-V1Q'      | 'CHIP'         | ''          | ''   | '20130805'  
 '4.7UH/13.5A'                  | 'SMLF'     | 'EMPTY'  | 'CV-47D5MZ00'(!)           = ''              | ''                 | 'CV-47D5MZ00'              |'L_MMD12FD'| 'NA'                           | 'IO'       | 'IND SMD 4.7UH20% 13.5A MMD-12FD-4R7M-V1Q'      | 'CHIP'         | ''          | ''   | '20130805'  
 '1.0UH/18A'                    | 'SMLF'     | 'IND'    | 'CV-10I0MZ01'(!)           = ''              | ''                 | 'CV-10I0MZ01'              |'L_PCMC104T'| '1.0UH/18A'                    | 'DISCRETE' | 'IND SMD 1.0UH +-20% 18A(PCMC104T-1R0MN)'       | 'CHIP'         | ''          | ''   | '20130806'  
 '1.0UH/18A'                    | 'SMLF'     | 'EMPTY'  | 'CV-10I0MZ01'(!)           = ''              | ''                 | 'CV-10I0MZ01'              |'L_PCMC104T'| 'NA'                           | 'IO'       | 'IND SMD 1.0UH +-20% 18A(PCMC104T-1R0MN)'       | 'CHIP'         | ''          | ''   | '20130806'  
 '28F0181-1SR-10/10A'           | 'SMLF'     | 'IND'    | 'CX11SR10000'(!)           = ''              | ''                 | 'CX11SR10000'              |'L_28F0181-1SR-10'| '28F0181-1SR-10/10A'           | 'DISCRETE' | 'EMI FILTER BEAD 28F0181-1SR-10 (115,10A)'      | 'CHIP'         | ''          | ''   | '20130828'  
 '28F0181-1SR-10/10A'           | 'SMLF'     | 'EMPTY'  | 'CX11SR10000'(!)           = ''              | ''                 | 'CX11SR10000'              |'L_28F0181-1SR-10'| 'NA'                           | 'IO'       | 'EMI FILTER BEAD 28F0181-1SR-10 (115,10A)'      | 'CHIP'         | ''          | ''   | '20130828'  
 '360NH/53A'                    | 'SMLF'     | 'IND'    | 'CV+36^0KZ02'(!)           = ''              | ''                 | 'CV+36^0KZ02'              |'L_HCUV138795L-271'| '360NH/53A'                    | 'DISCRETE' | 'IND SMD 360NH +-10% 53A(HCUV138795L-361'       | 'CHIP'         | ''          | ''   | '20131009'  
 '360NH/53A'                    | 'SMLF'     | 'EMPTY'  | 'CV+36^0KZ02'(!)           = ''              | ''                 | 'CV+36^0KZ02'              |'L_HCUV138795L-271'| 'NA'                           | 'IO'       | 'IND SMD 360NH +-10% 53A(HCUV138795L-361'       | 'CHIP'         | ''          | ''   | '20131009'  
 '470NH/40A'                    | 'SMLF'     | 'IND'    | 'CV+47^0KZ04'(!)           = ''              | ''                 | 'CV+47^0KZ04'              |'L_HCUV138795L-271'| '470NH/40A'                    | 'DISCRETE' | 'IND SMD 470NH +-10% 40A(HCUV138795L-471'       | 'CHIP'         | ''          | ''   | '20131009'  
 '470NH/40A'                    | 'SMLF'     | 'EMPTY'  | 'CV+47^0KZ04'(!)           = ''              | ''                 | 'CV+47^0KZ04'              |'L_HCUV138795L-271'| 'NA'                           | 'IO'       | 'IND SMD 470NH +-10% 40A(HCUV138795L-471'       | 'CHIP'         | ''          | ''   | '20131009'  
 'BLM18KG260TN1D/6A'            | 'SMLF'     | 'IND'    | 'CX8KG260000'(!)           = ''              | ''                 | 'CX8KG260000'              |'L0603'| 'BLM18KG260TN1D/6A'            | 'DISCRETE' | 'EMI FILTER BLM18KG260TN1D(26,6A)'              | 'CHIP'         | ''          | ''   | '20131016'  
 'BLM18KG260TN1D/6A'            | 'SMLF'     | 'EMPTY'  | 'CX8KG260000'(!)           = ''              | ''                 | 'CX8KG260000'              |'L0603'| 'NA'                           | 'IO'       | 'EMI FILTER BLM18KG260TN1D(26,6A)'              | 'CHIP'         | ''          | ''   | '20131016'  
 'BLM18KG601SN1D/1.3A'          | 'SMLF'     | 'IND'    | 'CX8KG601000'(!)           = 'End of Design' | 'Comp-Approve'     | 'CX8KG601000'              |'L0603'| 'BLM18KG601SN1D/1.3A'          | 'DISCRETE' | 'EMI FILTER BLM18KG601SN1D(600,1.3A)'           | 'CHIP'         | ''          | ''   | '20131016'  
 'BLM18KG601SN1D/1.3A'          | 'SMLF'     | 'EMPTY'  | 'CX8KG601000'(!)           = 'End of Design' | 'Comp-Approve'     | 'CX8KG601000'              |'L0603'| 'NA'                           | 'IO'       | 'EMI FILTER BLM18KG601SN1D(600,1.3A)'           | 'CHIP'         | ''          | ''   | '20131016'  
 'BLM18EG121SN1D/2A'            | 'SMLF'     | 'IND'    | 'CX8EG121000'(!)           = ''              | ''                 | 'CX8EG121000'              |'L0603'| 'BLM18EG121SN1D/2A'            | 'DISCRETE' | 'EMI FILTER BLM18EG121SN1D(120.2A)'             | 'CHIP'         | ''          | ''   | '20131016'  
 'BLM18EG121SN1D/2A'            | 'SMLF'     | 'EMPTY'  | 'CX8EG121000'(!)           = ''              | ''                 | 'CX8EG121000'              |'L0603'| 'NA'                           | 'IO'       | 'EMI FILTER BLM18EG121SN1D(120.2A)'             | 'CHIP'         | ''          | ''   | '20131016'  
 'HCB1608KF-471T10'             | 'SMLF'     | 'IND'    | 'CX471T10000'(!)           = ''              | ''                 | 'CX471T10000'              |'L0603'| 'HCB1608KF-471T10'             | 'DISCRETE' | 'EMI FILTER HCB1608KF-471T10(470,1000MA)'       | 'CHIP'         | ''          | ''   | '20131017'  
 'HCB1608KF-471T10'             | 'SMLF'     | 'EMPTY'  | 'CX471T10000'(!)           = ''              | ''                 | 'CX471T10000'              |'L0603'| 'NA'                           | 'IO'       | 'EMI FILTER HCB1608KF-471T10(470,1000MA)'       | 'CHIP'         | ''          | ''   | '20131017'  
 'PBY160808T-181Y-N/2000MA'     | 'SMLF'     | 'IND'    | 'CX08T181002'(!)           = ''              | ''                 | 'CX08T181002'              |'L0603'| 'PBY160808T-181Y-N/2000MA'     | 'DISCRETE' | 'EMI FILTER PBY160808T-181Y-N(180,2000MA)'      | 'CHIP'         | ''          | ''   | '20131029'  
 'PBY160808T-181Y-N/2000MA'     | 'SMLF'     | 'EMPTY'  | 'CX08T181002'(!)           = ''              | ''                 | 'CX08T181002'              |'L0603'| 'NA'                           | 'IO'       | 'EMI FILTER PBY160808T-181Y-N(180,2000MA)'      | 'CHIP'         | ''          | ''   | '20131029'  
 '2.2UH/790MA'                  | 'SMLF'     | 'IND'    | 'CV-2208MZ01'(!)           = ''              | ''                 | 'CV-2208MZ01'              |'L1210XC'| '2.2UH/790MA'                  | 'DISCRETE' | 'IND SMD 2.2UH 20% 790MA(LQH32CN2R2M33L)'       | 'CHIP'         | ''          | ''   | '20131021'  
 '2.2UH/790MA'                  | 'SMLF'     | 'EMPTY'  | 'CV-2208MZ01'(!)           = ''              | ''                 | 'CV-2208MZ01'              |'L1210XC'| 'NA'                           | 'IO'       | 'IND SMD 2.2UH 20% 790MA(LQH32CN2R2M33L)'       | 'CHIP'         | ''          | ''   | '20131021'  
 '0.45UF/25A'                   | 'SMLF'     | 'IND'    | 'CV+45Q0MZ02'(!)           = ''              | ''                 | 'CV+45Q0MZ02'              |'L_MMD-10DZ-R45M-X2Q'| '0.45UF/25A'                   | 'DISCRETE' | 'IND 0.45U +-20% 25A(MMD-10DZ-R45M-X2Q)'        | 'CHIP'         | ''          | ''   | '20131105'  
 '0.45UF/25A'                   | 'SMLF'     | 'EMPTY'  | 'CV+45Q0MZ02'(!)           = ''              | ''                 | 'CV+45Q0MZ02'              |'L_MMD-10DZ-R45M-X2Q'| 'NA'                           | 'IO'       | 'IND 0.45U +-20% 25A(MMD-10DZ-R45M-X2Q)'        | 'CHIP'         | ''          | ''   | '20131105'  
 '180NH/75A'                    | 'SMLF'     | 'IND'    | 'CV+18^0KZ03'(!)           = ''              | ''                 | 'CV+18^0KZ03'              |'L_HCUV117595'| '180NH/75A'                    | 'DISCRETE' | 'IND SMD 180NH +-10% 75A(HCUV117595-181B)'      | 'CHIP'         | ''          | ''   | '20131204'  
 '180NH/75A'                    | 'SMLF'     | 'EMPTY'  | 'CV+18^0KZ03'(!)           = ''              | ''                 | 'CV+18^0KZ03'              |'L_HCUV117595'| 'NA'                           | 'IO'       | 'IND SMD 180NH +-10% 75A(HCUV117595-181B)'      | 'CHIP'         | ''          | ''   | '20131204'  
 'FCM2012KF-601T/0.5A'          | 'SMLF'     | 'IND'    | 'CX601T05003'(!)           = ''              | ''                 | 'CX601T05003'              |'L0805'| 'FCM2012KF-601T/0.5A'          | 'DISCRETE' | 'EMI FILTER FCM2012KF-601T05(600,0.5A)'         | 'CHIP'         | ''          | ''   | '20131206'  
 'FCM2012KF-601T/0.5A'          | 'SMLF'     | 'EMPTY'  | 'CX601T05003'(!)           = ''              | ''                 | 'CX601T05003'              |'L0805'| 'NA'                           | 'IO'       | 'EMI FILTER FCM2012KF-601T05(600,0.5A)'         | 'CHIP'         | ''          | ''   | '20131206'  
 '3.3UH/4A'                     | 'SMLF'     | 'IND'    | 'CV-3340MZ01'(!)           = ''              | ''                 | 'CV-3340MZ01'              |'L_PCMB042T'| '3.3UH/4A'                     | 'DISCRETE' | 'IND SMD 3.3UH +-20% 4A PIMB042T-3R3MS'         | 'CHIP'         | ''          | ''   | '20131211'  
 '3.3UH/4A'                     | 'SMLF'     | 'EMPTY'  | 'CV-3340MZ01'(!)           = ''              | ''                 | 'CV-3340MZ01'              |'L_PCMB042T'| 'NA'                           | 'IO'       | 'IND SMD 3.3UH +-20% 4A PIMB042T-3R3MS'         | 'CHIP'         | ''          | ''   | '20131211'  
 '6.8UH/2.8A'                   | 'SMLF'     | 'IND'    | 'CV-6828MZ02'(!)           = ''              | ''                 | 'CV-6828MZ02'              |'L_MMD-05AH'| '6.8UH/2.8A'                   | 'DISCRETE' | 'IND SMD 6.8UH+-20%2.8A MMD-05AH-6R8M-X2Q'      | 'CHIP'         | ''          | ''   | '20131211'  
 '6.8UH/2.8A'                   | 'SMLF'     | 'EMPTY'  | 'CV-6828MZ02'(!)           = ''              | ''                 | 'CV-6828MZ02'              |'L_MMD-05AH'| 'NA'                           | 'IO'       | 'IND SMD 6.8UH+-20%2.8A MMD-05AH-6R8M-X2Q'      | 'CHIP'         | ''          | ''   | '20131211'  
 '1.0UH/9A'                     | 'SMLF'     | 'IND'    | 'CV-1090MZ00'(!)           = ''              | ''                 | 'CV-1090MZ00'              |'L_PCMB062D'| '1.0UH/9A'                     | 'DISCRETE' | 'IND SMD 1.0UH +-20% 9A(PCMB062D-1R0MS)'        | 'CHIP'         | ''          | ''   | '20131211'  
 '1.0UH/9A'                     | 'SMLF'     | 'EMPTY'  | 'CV-1090MZ00'(!)           = ''              | ''                 | 'CV-1090MZ00'              |'L_PCMB062D'| 'NA'                           | 'IO'       | 'IND SMD 1.0UH +-20% 9A(PCMB062D-1R0MS)'        | 'CHIP'         | ''          | ''   | '20131211'  
 '1.5UH/6A'                     | 'SMLF'     | 'IND'    | 'CV-1560MZ01'(!)           = ''              | ''                 | 'CV-1560MZ01'              |'L_CMME053T_4-5X4-7'| '1.5UH/6A'                     | 'DISCRETE' | 'IND SMD 1.5UH +-20% 6A(PCMB053T-1R5MS)'        | 'CHIP'         | ''          | ''   | '20131213'  
 '1.5UH/6A'                     | 'SMLF'     | 'EMPTY'  | 'CV-1560MZ01'(!)           = ''              | ''                 | 'CV-1560MZ01'              |'L_CMME053T_4-5X4-7'| 'NA'                           | 'IO'       | 'IND SMD 1.5UH +-20% 6A(PCMB053T-1R5MS)'        | 'CHIP'         | ''          | ''   | '20131213'  
 '2.2UH/7A'                     | 'SMLF'     | 'IND'    | 'CV-2270MZ05'(!)           = ''              | ''                 | 'CV-2270MZ05'              |'L_PCMB062D'| '2.2UH/7A'                     | 'DISCRETE' | 'IND SMD 2.2UH +-20% 7A PCMB062D-2R2MS'         | 'CHIP'         | ''          | ''   | '20131217'  
 '2.2UH/7A'                     | 'SMLF'     | 'EMPTY'  | 'CV-2270MZ05'(!)           = ''              | ''                 | 'CV-2270MZ05'              |'L_PCMB062D'| 'NA'                           | 'IO'       | 'IND SMD 2.2UH +-20% 7A PCMB062D-2R2MS'         | 'CHIP'         | ''          | ''   | '20131217'  
 '3.3UH/13A'                    | 'SMLF'     | 'IND'    | 'CV-33D0MZ01'(!)           = ''              | ''                 | 'CV-33D0MZ01'              |'L_PCMB062D'| '3.3UH/13A'                    | 'DISCRETE' | 'IND SMD 3.3UH +-20% 13A(PCMB062D-3R3MS)'       | 'CHIP'         | ''          | ''   | '20131217'  
 '3.3UH/13A'                    | 'SMLF'     | 'EMPTY'  | 'CV-33D0MZ01'(!)           = ''              | ''                 | 'CV-33D0MZ01'              |'L_PCMB062D'| 'NA'                           | 'IO'       | 'IND SMD 3.3UH +-20% 13A(PCMB062D-3R3MS)'       | 'CHIP'         | ''          | ''   | '20131217'  
 '2.2UH/22A'                    | 'SMLF'     | 'IND'    | 'CV-22M0MZ01'(!)           = ''              | ''                 | 'CV-22M0MZ01'              |'L_PCMS136E'| '2.2UH/22A'                    | 'DISCRETE' | 'IND SMD 2.2UH +-20% 22A PCMS136E-2R2MF'        | 'CHIP'         | ''          | ''   | '20140114'  
 '2.2UH/22A'                    | 'SMLF'     | 'EMPTY'  | 'CV-22M0MZ01'(!)           = ''              | ''                 | 'CV-22M0MZ01'              |'L_PCMS136E'| 'NA'                           | 'IO'       | 'IND SMD 2.2UH +-20% 22A PCMS136E-2R2MF'        | 'CHIP'         | ''          | ''   | '20140114'  
 '3.3UH/19A'                    | 'SMLF'     | 'IND'    | 'CV-33J0MZ00'(!)           = ''              | ''                 | 'CV-33J0MZ00'              |'L_PCMS136E'| '3.3UH/19A'                    | 'DISCRETE' | 'IND SMD 3.3UH +-20% 19A PCMS136E-3R3MF'        | 'CHIP'         | ''          | ''   | '20140114'  
 '3.3UH/19A'                    | 'SMLF'     | 'EMPTY'  | 'CV-33J0MZ00'(!)           = ''              | ''                 | 'CV-33J0MZ00'              |'L_PCMS136E'| 'NA'                           | 'IO'       | 'IND SMD 3.3UH +-20% 19A PCMS136E-3R3MF'        | 'CHIP'         | ''          | ''   | '20140114'  
 '6.8UH/11.5A'                  | 'SMLF'     | 'IND'    | 'CV-68B5MZ00'(!)           = ''              | ''                 | 'CV-68B5MZ00'              |'L_MMD12FD'| '6.8UH/11.5A'                  | 'DISCRETE' | 'IND SMD 6.8UH +-20% 11.5A MMD-12FD-6R8M'       | 'CHIP'         | ''          | ''   | '20140205'  
 '6.8UH/11.5A'                  | 'SMLF'     | 'EMPTY'  | 'CV-68B5MZ00'(!)           = ''              | ''                 | 'CV-68B5MZ00'              |'L_MMD12FD'| 'NA'                           | 'IO'       | 'IND SMD 6.8UH +-20% 11.5A MMD-12FD-6R8M'       | 'CHIP'         | ''          | ''   | '20140205'  
 '0.1UH/11.5A'                  | 'SMLF'     | 'IND'    | 'CV+1012MZ00'(!)           = ''              | ''                 | 'CV+1012MZ00'              |'L_MMD-04AB'| '0.1UH/11.5A'                  | 'DISCRETE' | 'IND SMD 0.1UH 20% 11.5A MMD-04AB-R10M-V1'      | 'CHIP'         | ''          | ''   | '20140205'  
 '0.1UH/11.5A'                  | 'SMLF'     | 'EMPTY'  | 'CV+1012MZ00'(!)           = ''              | ''                 | 'CV+1012MZ00'              |'L_MMD-04AB'| 'NA'                           | 'IO'       | 'IND SMD 0.1UH 20% 11.5A MMD-04AB-R10M-V1'      | 'CHIP'         | ''          | ''   | '20140205'  
 '4.7UH/8A'                     | 'SMLF'     | 'IND'    | 'CV-4780MZ04'(!)           = ''              | ''                 | 'CV-4780MZ04'              |'L_MMD-08DZ'| '4.7UH/8A'                     | 'DISCRETE' | 'IND SMD 4.7UH 20% 8A MMD-08DZ-4R7M-V2Q'        | 'CHIP'         | ''          | ''   | '20140205'  
 '4.7UH/8A'                     | 'SMLF'     | 'EMPTY'  | 'CV-4780MZ04'(!)           = ''              | ''                 | 'CV-4780MZ04'              |'L_MMD-08DZ'| 'NA'                           | 'IO'       | 'IND SMD 4.7UH 20% 8A MMD-08DZ-4R7M-V2Q'        | 'CHIP'         | ''          | ''   | '20140205'  
 '7.3UH/12A'                    | 'SMLF'     | 'IND'    | 'CV-73C0MZ00'(!)           = ''              | ''                 | 'CV-73C0MZ00'              |'L_HAH1378'| '7.3UH/12A'                    | 'DISCRETE' | 'IND SMD 7.3UH +-20% 12A(HAH1378-7R3)'          | 'CHIP'         | ''          | ''   | '20140205'  
 '7.3UH/12A'                    | 'SMLF'     | 'EMPTY'  | 'CV-73C0MZ00'(!)           = ''              | ''                 | 'CV-73C0MZ00'              |'L_HAH1378'| 'NA'                           | 'IO'       | 'IND SMD 7.3UH +-20% 12A(HAH1378-7R3)'          | 'CHIP'         | ''          | ''   | '20140205'  
 '1.5UH/13.3A'                  | 'SMLF'     | 'IND'    | 'CV-15D3MZ00'(!)           = ''              | ''                 | 'CV-15D3MZ00'              |'L_HAH85'| '1.5UH/13.3A'                  | 'DISCRETE' | 'IND SMD 1.5UH +-20% 13.3A(HAH85-1R5)'          | 'CHIP'         | ''          | ''   | '20140205'  
 '1.5UH/13.3A'                  | 'SMLF'     | 'EMPTY'  | 'CV-15D3MZ00'(!)           = ''              | ''                 | 'CV-15D3MZ00'              |'L_HAH85'| 'NA'                           | 'IO'       | 'IND SMD 1.5UH +-20% 13.3A(HAH85-1R5)'          | 'CHIP'         | ''          | ''   | '20140205'  
 '0.15UH/36A'                   | 'SMLF'     | 'IND'    | 'CV+15^0MZ07'(!)           = ''              | ''                 | 'CV+15^0MZ07'              |'L_PCME064T'| '0.15UH/36A'                   | 'DISCRETE' | 'IND SMD0.15U20%,36A(PCME064T-R15MS0R667)'      | 'CHIP'         | ''          | ''   | '20140218'  
 '0.15UH/36A'                   | 'SMLF'     | 'EMPTY'  | 'CV+15^0MZ07'(!)           = ''              | ''                 | 'CV+15^0MZ07'              |'L_PCME064T'| 'NA'                           | 'IO'       | 'IND SMD0.15U20%,36A(PCME064T-R15MS0R667)'      | 'CHIP'         | ''          | ''   | '20140218'  
 '470NH/25A'                    | 'SMLF'     | 'IND'    | 'CV+47Q0KZ00'(!)           = ''              | ''                 | 'CV+47Q0KZ00'              |'L_HCUVD6595-471'| '470NH/25A'                    | 'DISCRETE' | 'IND SMD 470NH +-10% 25A(HCUVD6595-471)'        | 'CHIP'         | ''          | ''   | '20140312'  
 '470NH/25A'                    | 'SMLF'     | 'EMPTY'  | 'CV+47Q0KZ00'(!)           = ''              | ''                 | 'CV+47Q0KZ00'              |'L_HCUVD6595-471'| 'NA'                           | 'IO'       | 'IND SMD 470NH +-10% 25A(HCUVD6595-471)'        | 'CHIP'         | ''          | ''   | '20140312'  
 'BLM15AG601SN1D/300MA'         | 'SMLF'     | 'IND'    | 'CX5AG601004'(!)           = ''              | ''                 | 'CX5AG601004'              |'L0402'| 'BLM15AG601SN1D/300MA'         | 'DISCRETE' | 'EMI FILTER BLM15AG601SN1D(600.300MA)'          | 'CHIP'         | ''          | ''   | '20140416'  
 'BLM15AG601SN1D/300MA'         | 'SMLF'     | 'EMPTY'  | 'CX5AG601004'(!)           = ''              | ''                 | 'CX5AG601004'              |'L0402'| 'NA'                           | 'IO'       | 'EMI FILTER BLM15AG601SN1D(600.300MA)'          | 'CHIP'         | ''          | ''   | '20140416'  
 '220NH/45A'                    | 'SMLF'     | 'IND'    | 'CV+22^0KZ03'(!)           = ''              | ''                 | 'CV+22^0KZ03'              |'L_HCUV117595'| '220NH/45A'                    | 'DISCRETE' | 'IND SMD 220NH +-10% 45A(HCUV117595-221A)'      | 'CHIP'         | ''          | ''   | '20140424'  
 '220NH/45A'                    | 'SMLF'     | 'EMPTY'  | 'CV+22^0KZ03'(!)           = ''              | ''                 | 'CV+22^0KZ03'              |'L_HCUV117595'| 'NA'                           | 'IO'       | 'IND SMD 220NH +-10% 45A(HCUV117595-221A)'      | 'CHIP'         | ''          | ''   | '20140424'  
 '0.47UH/63A'                   | 'SMLF'     | 'IND'    | 'CV+47^0MZ08'(!)           = ''              | ''                 | 'CV+47^0MZ08'              |'L_MMD12FD'| '0.47UH/63A'                   | 'DISCRETE' | 'IND SMD 0.47UH 20% 63A MMD-12FD-R47M-V1Q'      | 'CHIP'         | ''          | ''   | '20140428'  
 '0.47UH/63A'                   | 'SMLF'     | 'EMPTY'  | 'CV+47^0MZ08'(!)           = ''              | ''                 | 'CV+47^0MZ08'              |'L_MMD12FD'| 'NA'                           | 'IO'       | 'IND SMD 0.47UH 20% 63A MMD-12FD-R47M-V1Q'      | 'CHIP'         | ''          | ''   | '20140428'  
 'HCB2012KF-800T50/5A'          | 'SMLF'     | 'IND'    | 'CX000800506'(!)           = ''              | ''                 | 'CX000800506'              |'L0805'| 'HCB2012KF-800T50/5A'          | 'DISCRETE' | 'EMI FILTER CHIP HCB2012KF800T50(80,5A)'        | 'CHIP'         | ''          | ''   | '20140430'  
 'HCB2012KF-800T50/5A'          | 'SMLF'     | 'EMPTY'  | 'CX000800506'(!)           = ''              | ''                 | 'CX000800506'              |'L0805'| 'NA'                           | 'IO'       | 'EMI FILTER CHIP HCB2012KF800T50(80,5A)'        | 'CHIP'         | ''          | ''   | '20140430'  
 'HCB2012VF-800T50/5A'          | 'SMLF'     | 'IND'    | 'CX800T50000'(!)           = ''              | ''                 | 'CX800T50000'              |'L0805'| 'HCB2012VF-800T50/5A'          | 'DISCRETE' | 'EMI FILTER CHIP HCB2012VF-800T50(80,5A)'       | 'CHIP'         | ''          | ''   | '20140430'  
 'HCB2012VF-800T50/5A'          | 'SMLF'     | 'EMPTY'  | 'CX800T50000'(!)           = ''              | ''                 | 'CX800T50000'              |'L0805'| 'NA'                           | 'IO'       | 'EMI FILTER CHIP HCB2012VF-800T50(80,5A)'       | 'CHIP'         | ''          | ''   | '20140430'  
 'MHC2012S800UBP/5A'            | 'SMLF'     | 'IND'    | 'CX12S800000'(!)           = ''              | ''                 | 'CX12S800000'              |'L0805'| 'MHC2012S800UBP/5A'            | 'DISCRETE' | 'EMI FILTER MHC2012S800UBP(80,5A)'              | 'CHIP'         | ''          | ''   | '20140430'  
 'MHC2012S800UBP/5A'            | 'SMLF'     | 'EMPTY'  | 'CX12S800000'(!)           = ''              | ''                 | 'CX12S800000'              |'L0805'| 'NA'                           | 'IO'       | 'EMI FILTER MHC2012S800UBP(80,5A)'              | 'CHIP'         | ''          | ''   | '20140430'  
 '22UH/5A'                      | 'SMLF'     | 'IND'    | 'CV02250MZ01'(!)           = ''              | ''                 | 'CV02250MZ01'              |'L_PCMB104TXB'| '22UH/5A'                      | 'DISCRETE' | 'IND SMD 22UH+-20% 5A(PCMB104T-220MS)'          | 'CHIP'         | ''          | ''   | '20140508'  
 '22UH/5A'                      | 'SMLF'     | 'EMPTY'  | 'CV02250MZ01'(!)           = ''              | ''                 | 'CV02250MZ01'              |'L_PCMB104TXB'| 'NA'                           | 'IO'       | 'IND SMD 22UH+-20% 5A(PCMB104T-220MS)'          | 'CHIP'         | ''          | ''   | '20140508'  
 '10UH/4A'                      | 'SMLF'     | 'IND'    | 'CV01040MZ02'(!)           = ''              | ''                 | 'CV01040MZ02'              |'L_PCMB063T'| '10UH/4A'                      | 'DISCRETE' | 'IND SMD 10UH +-20%,4A(PCMB063T-100MS)'         | 'CHIP'         | ''          | ''   | '20140523'  
 '10UH/4A'                      | 'SMLF'     | 'EMPTY'  | 'CV01040MZ02'(!)           = ''              | ''                 | 'CV01040MZ02'              |'L_PCMB063T'| 'NA'                           | 'IO'       | 'IND SMD 10UH +-20%,4A(PCMB063T-100MS)'         | 'CHIP'         | ''          | ''   | '20140523'  
 '220NH/45A'                    | 'SMLF'     | 'IND'    | 'CV+22^0KZ08'(!)           = ''              | ''                 | 'CV+22^0KZ08'              |'L_HCUV117595'| '220NH/45A'                    | 'DISCRETE' | 'IND SMD 220NH +-10% 45A(HCUV117595-221B)'      | 'CHIP'         | ''          | ''   | '20140623'  
 '220NH/45A'                    | 'SMLF'     | 'EMPTY'  | 'CV+22^0KZ08'(!)           = ''              | ''                 | 'CV+22^0KZ08'              |'L_HCUV117595'| 'NA'                           | 'IO'       | 'IND SMD 220NH +-10% 45A(HCUV117595-221B)'      | 'CHIP'         | ''          | ''   | '20140623'  
 '195NH/45A'                    | 'SMLF'     | 'IND'    | 'CV+19^0KZ00'(!)           = ''              | ''                 | 'CV+19^0KZ00'              |'L_HCUV117595'| '195NH/45A'                    | 'DISCRETE' | 'IND SMD 195NH +-10% 45A(HCUV117595-201)'       | 'CHIP'         | ''          | ''   | '20140702'  
 '195NH/45A'                    | 'SMLF'     | 'EMPTY'  | 'CV+19^0KZ00'(!)           = ''              | ''                 | 'CV+19^0KZ00'              |'L_HCUV117595'| 'NA'                           | 'IO'       | 'IND SMD 195NH +-10% 45A(HCUV117595-201)'       | 'CHIP'         | ''          | ''   | '20140702'  
 '0.45UH/45A'                   | 'SMLF'     | 'IND'    | 'CV+45^0MZ09'(!)           = 'Non-Preferred' | 'End of Life'      | 'CV+45^0MZ09'              |'L_L30909-4_EOL'| '0.45UH/45A'                   | 'DISCRETE' | 'IND SMD 0.45UH, +-20%, 45A(L30909-4)'          | 'CHIP'         | ''          | ''   | '20140702'  
 '0.45UH/45A'                   | 'SMLF'     | 'EMPTY'  | 'CV+45^0MZ09'(!)           = 'Non-Preferred' | 'End of Life'      | 'CV+45^0MZ09'              |'L_L30909-4_EOL'| 'NA'                           | 'IO'       | 'IND SMD 0.45UH, +-20%, 45A(L30909-4)'          | 'CHIP'         | ''          | ''   | '20140702'  
 '1UH/2.7A'                     | 'SMLF'     | 'IND'    | 'CV-1027MZ03'(!)           = ''              | ''                 | 'CV-1027MZ03'              |'L_DFP252012TF_2-5X2'| '1UH/2.7A'                     | 'DISCRETE' | 'IND SMD 1U 20%2.7A(DFP252012TF-1R0M-2A7)'      | 'CHIP'         | ''          | ''   | '20140709'  
 '1UH/2.7A'                     | 'SMLF'     | 'EMPTY'  | 'CV-1027MZ03'(!)           = ''              | ''                 | 'CV-1027MZ03'              |'L_DFP252012TF_2-5X2'| 'NA'                           | 'IO'       | 'IND SMD 1U 20%2.7A(DFP252012TF-1R0M-2A7)'      | 'CHIP'         | ''          | ''   | '20140709'  
 'HCB1608KF-221T20/2000MA'      | 'SMLF'     | 'IND'    | 'CX221T20001'(!)           = ''              | ''                 | 'CX221T20001'              |'L0603'| 'HCB1608KF-221T20/2000MA'      | 'DISCRETE' | 'EMI FILTER HCB1608KF-221T20(220,2000MA)'       | 'CHIP'         | ''          | ''   | '20140711'  
 'HCB1608KF-221T20/2000MA'      | 'SMLF'     | 'EMPTY'  | 'CX221T20001'(!)           = ''              | ''                 | 'CX221T20001'              |'L0603'| 'NA'                           | 'IO'       | 'EMI FILTER HCB1608KF-221T20(220,2000MA)'       | 'CHIP'         | ''          | ''   | '20140711'  
 '270NH/32A'                    | 'SMLF'     | 'IND'    | 'CV+27X0KZ00'(!)           = ''              | ''                 | 'CV+27X0KZ00'              |'L_HCUV106411-401G'| '270NH/32A'                    | 'DISCRETE' | 'IND SMD 270NH +-10% 32A(HCUV106411-271)'       | 'CHIP'         | ''          | ''   | '20140714'  
 '270NH/32A'                    | 'SMLF'     | 'EMPTY'  | 'CV+27X0KZ00'(!)           = ''              | ''                 | 'CV+27X0KZ00'              |'L_HCUV106411-401G'| 'NA'                           | 'IO'       | 'IND SMD 270NH +-10% 32A(HCUV106411-271)'       | 'CHIP'         | ''          | ''   | '20140714'  
 '1.5UH/6A'                     | 'SMLF'     | 'IND'    | 'CV-1560MZ00'(!)           = ''              | ''                 | 'CV-1560MZ00'              |'L_MMD-05CZ-2R2M-X1Q'| '1.5UH/6A'                     | 'DISCRETE' | 'IND SMD 1.5UH 20% 6A MMD-05CZ-1R5M-X1Q'        | 'CHIP'         | ''          | ''   | '20140714'  
 '1.5UH/6A'                     | 'SMLF'     | 'EMPTY'  | 'CV-1560MZ00'(!)           = ''              | ''                 | 'CV-1560MZ00'              |'L_MMD-05CZ-2R2M-X1Q'| 'NA'                           | 'IO'       | 'IND SMD 1.5UH 20% 6A MMD-05CZ-1R5M-X1Q'        | 'CHIP'         | ''          | ''   | '20140714'  
 '195NH/61A'                    | 'SMLF'     | 'IND'    | 'CV+19^0KZ01'(!)           = ''              | ''                 | 'CV+19^0KZ01'              |'L_FP1110V1_10-7X7-5'| '195NH/61A'                    | 'DISCRETE' | 'IND SMD 195NH +-10% 61A(FP1110V1-R20-R)'       | 'CHIP'         | ''          | ''   | '20140717'  
 '195NH/61A'                    | 'SMLF'     | 'EMPTY'  | 'CV+19^0KZ01'(!)           = ''              | ''                 | 'CV+19^0KZ01'              |'L_FP1110V1_10-7X7-5'| 'NA'                           | 'IO'       | 'IND SMD 195NH +-10% 61A(FP1110V1-R20-R)'       | 'CHIP'         | ''          | ''   | '20140717'  
 '1000UH/0.08A'                 | 'SMLF'     | 'IND'    | 'CV21001MZ00'(!)           = ''              | ''                 | 'CV21001MZ00'              |'L_LPS5015'| '1000UH/0.08A'                 | 'DISCRETE' | 'IND SMD 1000UH +-20% 0.08A LPS5015-105ML'      | 'CHIP'         | ''          | ''   | '20140731'  
 '1000UH/0.08A'                 | 'SMLF'     | 'EMPTY'  | 'CV21001MZ00'(!)           = ''              | ''                 | 'CV21001MZ00'              |'L_LPS5015'| 'NA'                           | 'IO'       | 'IND SMD 1000UH +-20% 0.08A LPS5015-105ML'      | 'CHIP'         | ''          | ''   | '20140731'  
 '0.8UH/66A'                    | 'SMLF'     | 'IND'    | 'CV+80^0KZ00'(!)           = ''              | ''                 | 'CV+80^0KZ00'              |'L_HCBD141312'| '0.8UH/66A'                    | 'DISCRETE' | 'IND SMD 0.8UH +-10% 66A(HCBD141312-801)'       | 'CHIP'         | ''          | ''   | '20140801'  
 '0.8UH/66A'                    | 'SMLF'     | 'EMPTY'  | 'CV+80^0KZ00'(!)           = ''              | ''                 | 'CV+80^0KZ00'              |'L_HCBD141312'| 'NA'                           | 'IO'       | 'IND SMD 0.8UH +-10% 66A(HCBD141312-801)'       | 'CHIP'         | ''          | ''   | '20140801'  
 '0.1UH/11.5A'                  | 'SMLF'     | 'IND'    | 'CV+10B5MZ00'(!)           = 'End of Design' | 'Comp-Approve'     | 'CV+10B5MZ00'              |'L_IHLP1616AB_4-45X4-06'| '0.1UH/11.5A'                  | 'DISCRETE' | 'IND SMD 0.1U +-20% 11.5A(IHLP1616ABERR10'      | 'CHIP'         | ''          | ''   | '20140806'  
 '0.1UH/11.5A'                  | 'SMLF'     | 'EMPTY'  | 'CV+10B5MZ00'(!)           = 'End of Design' | 'Comp-Approve'     | 'CV+10B5MZ00'              |'L_IHLP1616AB_4-45X4-06'| 'NA'                           | 'IO'       | 'IND SMD 0.1U +-20% 11.5A(IHLP1616ABERR10'      | 'CHIP'         | ''          | ''   | '20140806'  
 'PBY160808T-221Y-N/2A'         | 'SMLF'     | 'IND'    | 'CX08T221000'(!)           = ''              | ''                 | 'CX08T221000'              |'L0603'| 'PBY160808T-221Y-N/2A'         | 'DISCRETE' | 'EMI FILTER PBY160808T-221Y-N(220,2A)'          | 'CHIP'         | ''          | ''   | '20140808'  
 'PBY160808T-221Y-N/2A'         | 'SMLF'     | 'EMPTY'  | 'CX08T221000'(!)           = ''              | ''                 | 'CX08T221000'              |'L0603'| 'NA'                           | 'IO'       | 'EMI FILTER PBY160808T-221Y-N(220,2A)'          | 'CHIP'         | ''          | ''   | '20140808'  
 '1UH/10A'                      | 'SMLF'     | 'IND'    | 'TV-10A0MZ00'(!)           = ''              | ''                 | 'TV-10A0MZ00'              |'L_GLMC_6-5X6-5'| '1UH/10A'                      | 'DISCRETE' | 'IND SMD 1UH +-20% 10A(GLMC1R003A)EMSSEL'       | 'CHIP'         | ''          | ''   | '20140808'  
 '1UH/10A'                      | 'SMLF'     | 'EMPTY'  | 'TV-10A0MZ00'(!)           = ''              | ''                 | 'TV-10A0MZ00'              |'L_GLMC_6-5X6-5'| 'NA'                           | 'IO'       | 'IND SMD 1UH +-20% 10A(GLMC1R003A)EMSSEL'       | 'CHIP'         | ''          | ''   | '20140808'  
 'BLM18PG121SN1D/2000MA'        | 'SMLF'     | 'IND'    | 'CX8PG121009'(!)           = ''              | ''                 | 'CX8PG121009'              |'L0603'| 'BLM18PG121SN1D/2000MA'        | 'DISCRETE' | 'EMI FILTER BLM18PG121SN(120,2000MA)'           | 'CHIP'         | ''          | ''   | '20140812'  
 'BLM18PG121SN1D/2000MA'        | 'SMLF'     | 'EMPTY'  | 'CX8PG121009'(!)           = ''              | ''                 | 'CX8PG121009'              |'L0603'| 'NA'                           | 'IO'       | 'EMI FILTER BLM18PG121SN(120,2000MA)'           | 'CHIP'         | ''          | ''   | '20140812'  
 'HCP0805-1R5-R/13.3A'          | 'SMLF'     | 'IND'    | 'CV-15D3MZ01'(!)           = ''              | ''                 | 'CV-15D3MZ01'              |'L_HCP0805_7-7X7-4'| 'HCP0805-1R5-R/13.3A'          | 'DISCRETE' | 'IND SMD 1.5UF +-20% 13.3A(HCP0805-1R5-R)'      | 'CHIP'         | ''          | ''   | '20140812'  
 'HCP0805-1R5-R/13.3A'          | 'SMLF'     | 'EMPTY'  | 'CV-15D3MZ01'(!)           = ''              | ''                 | 'CV-15D3MZ01'              |'L_HCP0805_7-7X7-4'| 'NA'                           | 'IO'       | 'IND SMD 1.5UF +-20% 13.3A(HCP0805-1R5-R)'      | 'CHIP'         | ''          | ''   | '20140812'  
 '4.7UH/8.7A'                   | 'SMLF'     | 'IND'    | 'CV-4787MZ00'(!)           = ''              | ''                 | 'CV-4787MZ00'              |'L_IHLP3232DZ_8-18X8-18'| '4.7UH/8.7A'                   | 'DISCRETE' | 'IND SMD 4.7U +-20% 8.7A(IHLP3232DZER4R7M'      | 'CHIP'         | ''          | ''   | '20140812'  
 '4.7UH/8.7A'                   | 'SMLF'     | 'EMPTY'  | 'CV-4787MZ00'(!)           = ''              | ''                 | 'CV-4787MZ00'              |'L_IHLP3232DZ_8-18X8-18'| 'NA'                           | 'IO'       | 'IND SMD 4.7U +-20% 8.7A(IHLP3232DZER4R7M'      | 'CHIP'         | ''          | ''   | '20140812'  
 '65NH/24A'                     | 'SMLF'     | 'IND'    | 'TVA65P0EZ00'(!)           = ''              | 'End of Life'      | 'TVA65P0EZ00'              |'L_59PR65_3-8X3-8_EOL'| '65NH/24A'                     | 'DISCRETE' | 'IND SMD 65NH +-15% 24A(59PR65-650)SELEMS'      | 'CHIP'         | ''          | ''   | '20140812'  
 '65NH/24A'                     | 'SMLF'     | 'EMPTY'  | 'TVA65P0EZ00'(!)           = ''              | 'End of Life'      | 'TVA65P0EZ00'              |'L_59PR65_3-8X3-8_EOL'| 'NA'                           | 'IO'       | 'IND SMD 65NH +-15% 24A(59PR65-650)SELEMS'      | 'CHIP'         | ''          | ''   | '20140812'  
 'BLM18PG331SN1D/1200MA'        | 'SMLF'     | 'IND'    | 'CX8PG331000'(!)           = ''              | ''                 | 'CX8PG331000'              |'L0603'| 'BLM18PG331SN1D/1200MA'        | 'DISCRETE' | 'EMI FILTER BLM18PG331SN1D(330,1200MA)'         | 'CHIP'         | ''          | ''   | '20140819'  
 'BLM18PG331SN1D/1200MA'        | 'SMLF'     | 'EMPTY'  | 'CX8PG331000'(!)           = ''              | ''                 | 'CX8PG331000'              |'L0603'| 'NA'                           | 'IO'       | 'EMI FILTER BLM18PG331SN1D(330,1200MA)'         | 'CHIP'         | ''          | ''   | '20140819'  
 'HCB2012KF-601T20/2000MA'      | 'SMLF'     | 'IND'    | 'CX601T20000'(!)           = ''              | ''                 | 'CX601T20000'              |'L0805'| 'HCB2012KF-601T20/2000MA'      | 'DISCRETE' | 'EMI FILTER HCB2012KF-601T20(600,2000MA)'       | 'CHIP'         | ''          | ''   | '20140820'  
 'HCB2012KF-601T20/2000MA'      | 'SMLF'     | 'EMPTY'  | 'CX601T20000'(!)           = ''              | ''                 | 'CX601T20000'              |'L0805'| 'NA'                           | 'IO'       | 'EMI FILTER HCB2012KF-601T20(600,2000MA)'       | 'CHIP'         | ''          | ''   | '20140820'  
 '57511/33A'                    | 'SMLF'     | 'IND'    | 'CV-47Y0TZ00'(!)           = ''              | ''                 | 'CV-47Y0TZ00'              |'L_57511_30X19-3'| '57511/33A'                    | 'DISCRETE' | 'IND SMD 4.7UF +15%-25% 33A(57511)'             | 'CHIP'         | ''          | ''   | '20140820'  
 '57511/33A'                    | 'SMLF'     | 'EMPTY'  | 'CV-47Y0TZ00'(!)           = ''              | ''                 | 'CV-47Y0TZ00'              |'L_57511_30X19-3'| 'NA'                           | 'IO'       | 'IND SMD 4.7UF +15%-25% 33A(57511)'             | 'CHIP'         | ''          | ''   | '20140820'  
 '1UH/0.95A'                    | 'SMLF'     | 'IND'    | 'CV-1010MN00'(!)           = ''              | ''                 | 'CV-1010MN00'              |'L0603'| '1UH/0.95A'                    | 'DISCRETE' | 'IND CHIP 1U 20% 0.95A(LQM18PN1R0MFRL)'         | 'CHIP'         | ''          | ''   | '20140820'  
 '1UH/0.95A'                    | 'SMLF'     | 'EMPTY'  | 'CV-1010MN00'(!)           = ''              | ''                 | 'CV-1010MN00'              |'L0603'| 'NA'                           | 'IO'       | 'IND CHIP 1U 20% 0.95A(LQM18PN1R0MFRL)'         | 'CHIP'         | ''          | ''   | '20140820'  
 '0.56UH/6.5A'                  | 'SMLF'     | 'IND'    | 'CV+5665MZ00'(!)           = ''              | ''                 | 'CV+5665MZ00'              |'L_PCMB042T'| '0.56UH/6.5A'                  | 'DISCRETE' | 'IND SMD 0.56UH +-20% 6.5A(PCMB042T-R56MS'      | 'CHIP'         | ''          | ''   | '20140820'  
 '0.56UH/6.5A'                  | 'SMLF'     | 'EMPTY'  | 'CV+5665MZ00'(!)           = ''              | ''                 | 'CV+5665MZ00'              |'L_PCMB042T'| 'NA'                           | 'IO'       | 'IND SMD 0.56UH +-20% 6.5A(PCMB042T-R56MS'      | 'CHIP'         | ''          | ''   | '20140820'  
 'HC9-6R8-R/10.3A'              | 'SMLF'     | 'IND'    | 'CV-68A3EZ00'(!)           = ''              | ''                 | 'CV-68A3EZ00'              |'L_HC9_14-1X13-1'| 'HC9-6R8-R/10.3A'              | 'DISCRETE' | 'IND SMD 6.8UF +-15% 10.3A(HC9-6R8-R)'          | 'CHIP'         | ''          | ''   | '20140820'  
 'HC9-6R8-R/10.3A'              | 'SMLF'     | 'EMPTY'  | 'CV-68A3EZ00'(!)           = ''              | ''                 | 'CV-68A3EZ00'              |'L_HC9_14-1X13-1'| 'NA'                           | 'IO'       | 'IND SMD 6.8UF +-15% 10.3A(HC9-6R8-R)'          | 'CHIP'         | ''          | ''   | '20140820'  
 '0.128UH/22.2A'                | 'SMLF'     | 'IND'    | 'CV+12M2MZ00'(!)           = 'Non-Preferred' | 'End of Life'      | 'CV+12M2MZ00'              |'L_HCM0503_5-15X5-1_EOL'| '0.128UH/22.2A'                | 'DISCRETE' | 'IND SMD 0.128U +-20% 22.2A(HCM0503-R20-R'      | 'CHIP'         | ''          | ''   | '20140820'  
 '0.128UH/22.2A'                | 'SMLF'     | 'EMPTY'  | 'CV+12M2MZ00'(!)           = 'Non-Preferred' | 'End of Life'      | 'CV+12M2MZ00'              |'L_HCM0503_5-15X5-1_EOL'| 'NA'                           | 'IO'       | 'IND SMD 0.128U +-20% 22.2A(HCM0503-R20-R'      | 'CHIP'         | ''          | ''   | '20140820'  
 '100UH/0.9A'                   | 'SMLF'     | 'IND'    | 'TV11009MZ01'(!)           = 'Potential'     | 'End of Life'      | 'TV11009MZ01'              |'L_CLF7045T_7-2X6-9_EOL'| '100UH/0.9A'                   | 'DISCRETE' | 'IND SMD 100UH 20%,0.9A(CLF7045T)EMS SEL'       | 'CHIP'         | ''          | ''   | '20140827'  
 '100UH/0.9A'                   | 'SMLF'     | 'EMPTY'  | 'TV11009MZ01'(!)           = 'Potential'     | 'End of Life'      | 'TV11009MZ01'              |'L_CLF7045T_7-2X6-9_EOL'| 'NA'                           | 'IO'       | 'IND SMD 100UH 20%,0.9A(CLF7045T)EMS SEL'       | 'CHIP'         | ''          | ''   | '20140827'  
 'BLM21PG220SN1D/6A'            | 'SMLF'     | 'IND'    | 'CX1PG220004'(!)           = 'End of Design' | 'Comp-Approve'     | 'CX1PG220004'              |'L0805'| 'BLM21PG220SN1D/6A'            | 'DISCRETE' | 'EMI FILTER CHIP BLM21PG220SN1D(22 6A)'         | 'CHIP'         | ''          | ''   | '20140827'  
 'BLM21PG220SN1D/6A'            | 'SMLF'     | 'EMPTY'  | 'CX1PG220004'(!)           = 'End of Design' | 'Comp-Approve'     | 'CX1PG220004'              |'L0805'| 'NA'                           | 'IO'       | 'EMI FILTER CHIP BLM21PG220SN1D(22 6A)'         | 'CHIP'         | ''          | ''   | '20140827'  
 '270NH/61A'                    | 'SMLF'     | 'IND'    | 'CV+27^0KZ11'(!)           = 'End of Design' | 'Comp-Approve'     | 'CV+27^0KZ11'              |'L_FP1110V1_10-7X7-5'| '270NH/61A'                    | 'DISCRETE' | 'IND SMD 270NH +-10% 61A(FP1110V1-R27-R)'       | 'CHIP'         | ''          | ''   | '20140828'  
 '270NH/61A'                    | 'SMLF'     | 'EMPTY'  | 'CV+27^0KZ11'(!)           = 'End of Design' | 'Comp-Approve'     | 'CV+27^0KZ11'              |'L_FP1110V1_10-7X7-5'| 'NA'                           | 'IO'       | 'IND SMD 270NH +-10% 61A(FP1110V1-R27-R)'       | 'CHIP'         | ''          | ''   | '20140828'  
 '220NH/61A'                    | 'SMLF'     | 'IND'    | 'CV+22^0KZ09'(!)           = ''              | ''                 | 'CV+22^0KZ09'              |'L_FP1110V1_10-7X7-5'| '220NH/61A'                    | 'DISCRETE' | 'IND SMD 220NH +-10% 61A(FP1110V1-R22-R)'       | 'CHIP'         | ''          | ''   | '20140828'  
 '220NH/61A'                    | 'SMLF'     | 'EMPTY'  | 'CV+22^0KZ09'(!)           = ''              | ''                 | 'CV+22^0KZ09'              |'L_FP1110V1_10-7X7-5'| 'NA'                           | 'IO'       | 'IND SMD 220NH +-10% 61A(FP1110V1-R22-R)'       | 'CHIP'         | ''          | ''   | '20140828'  
 '4.7UH/650MA'                  | 'SMLF'     | 'IND'    | 'CV-4707MZ16'(!)           = ''              | ''                 | 'CV-4707MZ16'              |'L1210XC_H61'| '4.7UH/650MA'                  | 'DISCRETE' | 'IND SMD 4.7UH 20% 650MA(LQH32DN4R7M53L)'       | 'CHIP'         | ''          | ''   | '20140901'  
 '4.7UH/650MA'                  | 'SMLF'     | 'EMPTY'  | 'CV-4707MZ16'(!)           = ''              | ''                 | 'CV-4707MZ16'              |'L1210XC_H61'| 'NA'                           | 'IO'       | 'IND SMD 4.7UH 20% 650MA(LQH32DN4R7M53L)'       | 'CHIP'         | ''          | ''   | '20140901'  
 '2.2UH/970MA'                  | 'SMLF'     | 'IND'    | 'CV-2210TZ00'(!)           = ''              | ''                 | 'CV-2210TZ00'              |'L1210XB'| '2.2UH/970MA'                  | 'DISCRETE' | 'IND SMD 2.2UH 30% 970MA(LQH32PB2R2NN0L)'       | 'CHIP'         | ''          | ''   | '20140901'  
 '2.2UH/970MA'                  | 'SMLF'     | 'EMPTY'  | 'CV-2210TZ00'(!)           = ''              | ''                 | 'CV-2210TZ00'              |'L1210XB'| 'NA'                           | 'IO'       | 'IND SMD 2.2UH 30% 970MA(LQH32PB2R2NN0L)'       | 'CHIP'         | ''          | ''   | '20140901'  
 '320NH/61A'                    | 'SMLF'     | 'IND'    | 'CV+32^0KZ06'(!)           = ''              | ''                 | 'CV+32^0KZ06'              |'L_FP1110V1_10-7X7-5XA'| '320NH/61A'                    | 'DISCRETE' | 'IND SMD 320NH +-10% 61A(FP1110V1-R32-R)'       | 'CHIP'         | ''          | ''   | '20140903'  
 '320NH/61A'                    | 'SMLF'     | 'EMPTY'  | 'CV+32^0KZ06'(!)           = ''              | ''                 | 'CV+32^0KZ06'              |'L_FP1110V1_10-7X7-5XA'| 'NA'                           | 'IO'       | 'IND SMD 320NH +-10% 61A(FP1110V1-R32-R)'       | 'CHIP'         | ''          | ''   | '20140903'  
 '1.0UH/8.0A'                   | 'SMLF'     | 'IND'    | 'CV-1080MZ00'(!)           = ''              | ''                 | 'CV-1080MZ00'              |'L_XFL4020_4X4'| '1.0UH/8.0A'                   | 'DISCRETE' | 'IND SMD 1.0UH +-20% 8.0A(XFL4020-102MEC)'      | 'CHIP'         | ''          | ''   | '20140923'  
 '1.0UH/8.0A'                   | 'SMLF'     | 'EMPTY'  | 'CV-1080MZ00'(!)           = ''              | ''                 | 'CV-1080MZ00'              |'L_XFL4020_4X4'| 'NA'                           | 'IO'       | 'IND SMD 1.0UH +-20% 8.0A(XFL4020-102MEC)'      | 'CHIP'         | ''          | ''   | '20140923'  
 'NBQ160808T-601Y-N/0.2A'       | 'SMLF'     | 'IND'    | 'CX08T601001'(!)           = ''              | ''                 | 'CX08T601001'              |'L0603'| 'NBQ160808T-601Y-N/0.2A'       | 'DISCRETE' | 'EMI FILTER NBQ160808T-601Y-N(600,0.2A)'        | 'CHIP'         | ''          | ''   | '20140923'  
 'NBQ160808T-601Y-N/0.2A'       | 'SMLF'     | 'EMPTY'  | 'CX08T601001'(!)           = ''              | ''                 | 'CX08T601001'              |'L0603'| 'NA'                           | 'IO'       | 'EMI FILTER NBQ160808T-601Y-N(600,0.2A)'        | 'CHIP'         | ''          | ''   | '20140923'  
 '0.45UF/25A'                   | 'SMLF'     | 'IND'    | 'CV+45Q0MZ01'(!)           = ''              | ''                 | 'CV+45Q0MZ01'              |'L_PCMB104TXB'| '0.45UF/25A'                   | 'DISCRETE' | 'IND 0.45U(25A,+-20%,PCMB104T-R45MN)'           | 'CHIP'         | ''          | ''   | '20141001'  
 '0.45UF/25A'                   | 'SMLF'     | 'EMPTY'  | 'CV+45Q0MZ01'(!)           = ''              | ''                 | 'CV+45Q0MZ01'              |'L_PCMB104TXB'| 'NA'                           | 'IO'       | 'IND 0.45U(25A,+-20%,PCMB104T-R45MN)'           | 'CHIP'         | ''          | ''   | '20141001'  
 '2.2UH/0.95A'                  | 'SMLF'     | 'IND'    | 'CV-2210MN00'(!)           = ''              | 'End of Life'      | 'CV-2210MN00'              |'L0805_EOL'| '2.2UH/0.95A'                  | 'DISCRETE' | 'IND CHIP 2.2UH 20% 0.95A(CIG21L2R2MNE)'        | 'CHIP'         | ''          | ''   | '20141016'  
 '2.2UH/0.95A'                  | 'SMLF'     | 'EMPTY'  | 'CV-2210MN00'(!)           = ''              | 'End of Life'      | 'CV-2210MN00'              |'L0805_EOL'| 'NA'                           | 'IO'       | 'IND CHIP 2.2UH 20% 0.95A(CIG21L2R2MNE)'        | 'CHIP'         | ''          | ''   | '20141016'  
 '22NH/1.85MA'                  | 'SMLF'     | 'IND'    | 'CVA2219KN00'(!)           = 'End of Design' | 'End of Life'      | 'CVA2219KN00'              |'L0805_EOL'| '22NH/1.85MA'                  | 'DISCRETE' | 'IND CHIP 22NH 10% 1.85MA(MLH2012F22NKT)'       | 'CHIP'         | ''          | ''   | '20141016'  
 '22NH/1.85MA'                  | 'SMLF'     | 'EMPTY'  | 'CVA2219KN00'(!)           = 'End of Design' | 'End of Life'      | 'CVA2219KN00'              |'L0805_EOL'| 'NA'                           | 'IO'       | 'IND CHIP 22NH 10% 1.85MA(MLH2012F22NKT)'       | 'CHIP'         | ''          | ''   | '20141016'  
 '200NH/75A'                    | 'SMLF'     | 'IND'    | 'CV+20^0KZ01'(!)           = ''              | ''                 | 'CV+20^0KZ01'              |'L_HCUV117513_10-7X7-5'| '200NH/75A'                    | 'DISCRETE' | 'IND SMD 200NH +-10% 75A (HCUV117513-201)'      | 'CHIP'         | ''          | ''   | '20141022'  
 '200NH/75A'                    | 'SMLF'     | 'EMPTY'  | 'CV+20^0KZ01'(!)           = ''              | ''                 | 'CV+20^0KZ01'              |'L_HCUV117513_10-7X7-5'| 'NA'                           | 'IO'       | 'IND SMD 200NH +-10% 75A (HCUV117513-201)'      | 'CHIP'         | ''          | ''   | '20141022'  
 '160NH/98A'                    | 'SMLF'     | 'IND'    | 'CV+1698KZ00'(!)           = ''              | ''                 | 'CV+1698KZ00'              |'L_HCUVE117695_10-7X7-6'| '160NH/98A'                    | 'DISCRETE' | 'IND SMD 160NH +-10% 98A(HCUVE117695-161)'      | 'CHIP'         | ''          | ''   | '20141114'  
 '160NH/98A'                    | 'SMLF'     | 'EMPTY'  | 'CV+1698KZ00'(!)           = ''              | ''                 | 'CV+1698KZ00'              |'L_HCUVE117695_10-7X7-6'| 'NA'                           | 'IO'       | 'IND SMD 160NH +-10% 98A(HCUVE117695-161)'      | 'CHIP'         | ''          | ''   | '20141114'  
 '0.6UH/32.5A'                  | 'SMLF'     | 'IND'    | 'CV+6033KZ00'(!)           = ''              | ''                 | 'CV+6033KZ00'              |'L_HCUVD8095_8X8'| '0.6UH/32.5A'                  | 'DISCRETE' | 'IND SMD 0.6UH +-10% 32.5A(HCUVD8095-601)'      | 'CHIP'         | ''          | ''   | '201411'    
 '0.6UH/32.5A'                  | 'SMLF'     | 'EMPTY'  | 'CV+6033KZ00'(!)           = ''              | ''                 | 'CV+6033KZ00'              |'L_HCUVD8095_8X8'| 'NA'                           | 'IO'       | 'IND SMD 0.6UH +-10% 32.5A(HCUVD8095-601)'      | 'CHIP'         | ''          | ''   | '201411'    
 '0.1UH/17A'                    | 'SMLF'     | 'IND'    | 'CV+10H0MZ00'(!)           = ''              | ''                 | 'CV+10H0MZ00'              |'L_HCB444-101IN'| '0.1UH/17A'                    | 'DISCRETE' | 'IND SMD 0.1UH 20% 17A HCB444-101IN'            | 'CHIP'         | ''          | ''   | '20141201'  
 '0.1UH/17A'                    | 'SMLF'     | 'EMPTY'  | 'CV+10H0MZ00'(!)           = ''              | ''                 | 'CV+10H0MZ00'              |'L_HCB444-101IN'| 'NA'                           | 'IO'       | 'IND SMD 0.1UH 20% 17A HCB444-101IN'            | 'CHIP'         | ''          | ''   | '20141201'  
 '0.15UH/57A'                   | 'SMLF'     | 'IND'    | 'CV+15^0EZ02'(!)           = ''              | ''                 | 'CV+15^0EZ02'              |'L_HCB117555-151IN'| '0.15UH/57A'                   | 'DISCRETE' | 'IND SMD 0.15UH 15% 57A HCB117555-151IN'        | 'CHIP'         | ''          | ''   | '20141201'  
 '0.15UH/57A'                   | 'SMLF'     | 'EMPTY'  | 'CV+15^0EZ02'(!)           = ''              | ''                 | 'CV+15^0EZ02'              |'L_HCB117555-151IN'| 'NA'                           | 'IO'       | 'IND SMD 0.15UH 15% 57A HCB117555-151IN'        | 'CHIP'         | ''          | ''   | '20141201'  
 '3.3UH/13.5A'                  | 'SMLF'     | 'IND'    | 'CV-33D5MZ06'(!)           = ''              | ''                 | 'CV-33D5MZ06'              |'L_MPT730'| '3.3UH/13.5A'                  | 'DISCRETE' | 'IND SMD 3.3UH 20% 13.5A MPT730-3R3M1IN'        | 'CHIP'         | ''          | ''   | '20141201'  
 '3.3UH/13.5A'                  | 'SMLF'     | 'EMPTY'  | 'CV-33D5MZ06'(!)           = ''              | ''                 | 'CV-33D5MZ06'              |'L_MPT730'| 'NA'                           | 'IO'       | 'IND SMD 3.3UH 20% 13.5A MPT730-3R3M1IN'        | 'CHIP'         | ''          | ''   | '20141201'  
 '0.08UH/22A'                   | 'SMLF'     | 'IND'    | 'CVA80M0MZ00'(!)           = ''              | ''                 | 'CVA80M0MZ00'              |'L_HCB444-101IN'| '0.08UH/22A'                   | 'DISCRETE' | 'IND SMD 0.08UH 20% 22A HCB444-800IN'           | 'CHIP'         | ''          | ''   | '20141201'  
 '0.08UH/22A'                   | 'SMLF'     | 'EMPTY'  | 'CVA80M0MZ00'(!)           = ''              | ''                 | 'CVA80M0MZ00'              |'L_HCB444-101IN'| 'NA'                           | 'IO'       | 'IND SMD 0.08UH 20% 22A HCB444-800IN'           | 'CHIP'         | ''          | ''   | '20141201'  
 '270NH/64A'                    | 'SMLF'     | 'IND'    | 'CV+27^0KZ12'(!)           = ''              | ''                 | 'CV+27^0KZ12'              |'L_HCUV117512_10-7X7-5'| '270NH/64A'                    | 'DISCRETE' | 'IND SMD 270NH +-10% 64A(HCUV117512-271)'       | 'CHIP'         | ''          | ''   | '20141208'  
 '270NH/64A'                    | 'SMLF'     | 'EMPTY'  | 'CV+27^0KZ12'(!)           = ''              | ''                 | 'CV+27^0KZ12'              |'L_HCUV117512_10-7X7-5'| 'NA'                           | 'IO'       | 'IND SMD 270NH +-10% 64A(HCUV117512-271)'       | 'CHIP'         | ''          | ''   | '20141208'  
 '320NH/54A'                    | 'SMLF'     | 'IND'    | 'CV+32^0KZ08'(!)           = ''              | ''                 | 'CV+32^0KZ08'              |'L_HCUV117512_10-7X7-5'| '320NH/54A'                    | 'DISCRETE' | 'IND SMD 320NH +-10% 54A(HCUV117512-321)'       | 'CHIP'         | ''          | ''   | '20141208'  
 '320NH/54A'                    | 'SMLF'     | 'EMPTY'  | 'CV+32^0KZ08'(!)           = ''              | ''                 | 'CV+32^0KZ08'              |'L_HCUV117512_10-7X7-5'| 'NA'                           | 'IO'       | 'IND SMD 320NH +-10% 54A(HCUV117512-321)'       | 'CHIP'         | ''          | ''   | '20141208'  
 '400NH/43.5A'                  | 'SMLF'     | 'IND'    | 'CV+40^0KZ00'(!)           = ''              | ''                 | 'CV+40^0KZ00'              |'L_HCUV117512_10-7X7-5'| '400NH/43.5A'                  | 'DISCRETE' | 'IND SMD 400NH +-10% 43.5A(HCUV117512-401'      | 'CHIP'         | ''          | ''   | '20141208'  
 '400NH/43.5A'                  | 'SMLF'     | 'EMPTY'  | 'CV+40^0KZ00'(!)           = ''              | ''                 | 'CV+40^0KZ00'              |'L_HCUV117512_10-7X7-5'| 'NA'                           | 'IO'       | 'IND SMD 400NH +-10% 43.5A(HCUV117512-401'      | 'CHIP'         | ''          | ''   | '20141208'  
 '600NH/26A'                    | 'SMLF'     | 'IND'    | 'CV+60^0KZ00'(!)           = ''              | ''                 | 'CV+60^0KZ00'              |'L_HCUV117512_10-7X7-5'| '600NH/26A'                    | 'DISCRETE' | 'IND SMD 600NH +-10% 26A(HCUV117512-601)'       | 'CHIP'         | ''          | ''   | '20141208'  
 '600NH/26A'                    | 'SMLF'     | 'EMPTY'  | 'CV+60^0KZ00'(!)           = ''              | ''                 | 'CV+60^0KZ00'              |'L_HCUV117512_10-7X7-5'| 'NA'                           | 'IO'       | 'IND SMD 600NH +-10% 26A(HCUV117512-601)'       | 'CHIP'         | ''          | ''   | '20141208'  
 '220NH/81A'                    | 'SMLF'     | 'IND'    | 'CV+22^0KZ10'(!)           = ''              | ''                 | 'CV+22^0KZ10'              |'L_HCUV117512_10-7X7-5'| '220NH/81A'                    | 'DISCRETE' | 'IND SMD 220NH +-10% 81A(HCUV117512-221)'       | 'CHIP'         | ''          | ''   | '20141209'  
 '220NH/81A'                    | 'SMLF'     | 'EMPTY'  | 'CV+22^0KZ10'(!)           = ''              | ''                 | 'CV+22^0KZ10'              |'L_HCUV117512_10-7X7-5'| 'NA'                           | 'IO'       | 'IND SMD 220NH +-10% 81A(HCUV117512-221)'       | 'CHIP'         | ''          | ''   | '20141209'  
 '250NH/70A'                    | 'SMLF'     | 'IND'    | 'CV+25^0KZ02'(!)           = ''              | ''                 | 'CV+25^0KZ02'              |'L_HCUV117512_10-7X7-5'| '250NH/70A'                    | 'DISCRETE' | 'IND SMD 250NH +-10% 70A(HCUV117512-251)'       | 'CHIP'         | ''          | ''   | '20141209'  
 '250NH/70A'                    | 'SMLF'     | 'EMPTY'  | 'CV+25^0KZ02'(!)           = ''              | ''                 | 'CV+25^0KZ02'              |'L_HCUV117512_10-7X7-5'| 'NA'                           | 'IO'       | 'IND SMD 250NH +-10% 70A(HCUV117512-251)'       | 'CHIP'         | ''          | ''   | '20141209'  
 '470NH/36A'                    | 'SMLF'     | 'IND'    | 'CV+47^0KZ05'(!)           = ''              | ''                 | 'CV+47^0KZ05'              |'L_HCUV117512_10-7X7-5'| '470NH/36A'                    | 'DISCRETE' | 'IND SMD 470NH +-10% 36A(HCUV117512-471)'       | 'CHIP'         | ''          | ''   | '20141209'  
 '470NH/36A'                    | 'SMLF'     | 'EMPTY'  | 'CV+47^0KZ05'(!)           = ''              | ''                 | 'CV+47^0KZ05'              |'L_HCUV117512_10-7X7-5'| 'NA'                           | 'IO'       | 'IND SMD 470NH +-10% 36A(HCUV117512-471)'       | 'CHIP'         | ''          | ''   | '20141209'  
 '2.2UH/3A'                     | 'SMLF'     | 'IND'    | 'CV-2230MZ09'(!)           = ''              | ''                 | 'CV-2230MZ09'              |'L_IHLP1616AB_4-45X4-06'| '2.2UH/3A'                     | 'DISCRETE' | 'IND SMD 2.2UH +-20% 3A(IHLP1616ABER2R2M)'      | 'CHIP'         | ''          | ''   | '20141215'  
 '2.2UH/3A'                     | 'SMLF'     | 'EMPTY'  | 'CV-2230MZ09'(!)           = ''              | ''                 | 'CV-2230MZ09'              |'L_IHLP1616AB_4-45X4-06'| 'NA'                           | 'IO'       | 'IND SMD 2.2UH +-20% 3A(IHLP1616ABER2R2M)'      | 'CHIP'         | ''          | ''   | '20141215'  
 '2.2UH/12A'                    | 'SMLF'     | 'IND'    | 'CV-22C0MZ10'(!)           = ''              | ''                 | 'CV-22C0MZ10'              |'L_PCMB104TXB'| '2.2UH/12A'                    | 'DISCRETE' | 'IND SMD 2.2UH +-20% 12A(PIMC104T-2R2MN)'       | 'CHIP'         | ''          | ''   | '20141225'  
 '2.2UH/12A'                    | 'SMLF'     | 'EMPTY'  | 'CV-22C0MZ10'(!)           = ''              | ''                 | 'CV-22C0MZ10'              |'L_PCMB104TXB'| 'NA'                           | 'IO'       | 'IND SMD 2.2UH +-20% 12A(PIMC104T-2R2MN)'       | 'CHIP'         | ''          | ''   | '20141225'  
 'NBQ160808T-300Y-N/0.5A'       | 'SMLF'     | 'IND'    | 'CX08T300002'(!)           = ''              | ''                 | 'CX08T300002'              |'L0603'| 'NBQ160808T-300Y-N/0.5A'       | 'DISCRETE' | 'EMI FILTER NBQ160808T-300Y-N(30,0.5A)'         | 'CHIP'         | ''          | ''   | '20150303'  
 'NBQ160808T-300Y-N/0.5A'       | 'SMLF'     | 'EMPTY'  | 'CX08T300002'(!)           = ''              | ''                 | 'CX08T300002'              |'L0603'| 'NA'                           | 'IO'       | 'EMI FILTER NBQ160808T-300Y-N(30,0.5A)'         | 'CHIP'         | ''          | ''   | '20150303'  
 'BLM15AG100SN1D/1A'            | 'SMLF'     | 'IND'    | 'CX5AG100001'(!)           = ''              | ''                 | 'CX5AG100001'              |'L0402'| 'BLM15AG100SN1D/1A'            | 'DISCRETE' | 'EMI FILTER CHIP BLM15AG100SN1D(10,1A)'         | 'CHIP'         | ''          | ''   | '20150310'  
 'BLM15AG100SN1D/1A'            | 'SMLF'     | 'EMPTY'  | 'CX5AG100001'(!)           = ''              | ''                 | 'CX5AG100001'              |'L0402'| 'NA'                           | 'IO'       | 'EMI FILTER CHIP BLM15AG100SN1D(10,1A)'         | 'CHIP'         | ''          | ''   | '20150310'  
 '100UH/1.9A'                   | 'SMLF'     | 'IND'    | 'CV11019MZ00'(!)           = ''              | ''                 | 'CV11019MZ00'              |'L_MSCDRI-127F'| '100UH/1.9A'                   | 'DISCRETE' | 'IND SMD 100UH 20% 1.9A MSCDRI-127F-101M'       | 'CHIP'         | ''          | ''   | '20150331'  
 '100UH/1.9A'                   | 'SMLF'     | 'EMPTY'  | 'CV11019MZ00'(!)           = ''              | ''                 | 'CV11019MZ00'              |'L_MSCDRI-127F'| 'NA'                           | 'IO'       | 'IND SMD 100UH 20% 1.9A MSCDRI-127F-101M'       | 'CHIP'         | ''          | ''   | '20150331'  
 '120ohm/3A'                    | 'SMLF'     | 'IND'    | 'CX8SG121000'(!)           = 'End of Design' | 'Comp-Approve'     | 'CX8SG121000'              |'L0603'| '120ohm/3A'                    | 'DISCRETE' | 'EMI FILTER BEAD BLM18SG121TN1D(120.3A)'        | 'CHIP'         | ''          | ''   | '20150415'  
 '120ohm/3A'                    | 'SMLF'     | 'EMPTY'  | 'CX8SG121000'(!)           = 'End of Design' | 'Comp-Approve'     | 'CX8SG121000'              |'L0603'| 'NA'                           | 'IO'       | 'EMI FILTER BEAD BLM18SG121TN1D(120.3A)'        | 'CHIP'         | ''          | ''   | '20150415'  
 '0.15UH/35A'                   | 'SMLF'     | 'IND'    | 'CV+15^0KZ04'(!)           = ''              | ''                 | 'CV+15^0KZ04'              |'L_HCUVE575775_5-7X5-7'| '0.15UH/35A'                   | 'DISCRETE' | 'IND SMD 0.15UH 10% 35A(HCUVE575775-151)'       | 'CHIP'         | ''          | ''   | '20150415'  
 '0.15UH/35A'                   | 'SMLF'     | 'EMPTY'  | 'CV+15^0KZ04'(!)           = ''              | ''                 | 'CV+15^0KZ04'              |'L_HCUVE575775_5-7X5-7'| 'NA'                           | 'IO'       | 'IND SMD 0.15UH 10% 35A(HCUVE575775-151)'       | 'CHIP'         | ''          | ''   | '20150415'  
 'BLM18SG260TN1D/6A'            | 'SMLF'     | 'IND'    | 'CX8SG260000'(!)           = 'End of Design' | 'Comp-Approve'     | 'CX8SG260000'              |'L0603'| 'BLM18SG260TN1D/6A'            | 'DISCRETE' | 'EMI FILTER BLM18SG260TN1D(26,6A)'              | 'CHIP'         | ''          | ''   | '20150416'  
 'BLM18SG260TN1D/6A'            | 'SMLF'     | 'EMPTY'  | 'CX8SG260000'(!)           = 'End of Design' | 'Comp-Approve'     | 'CX8SG260000'              |'L0603'| 'NA'                           | 'IO'       | 'EMI FILTER BLM18SG260TN1D(26,6A)'              | 'CHIP'         | ''          | ''   | '20150416'  
 '1.5UH/16A'                    | 'SMLF'     | 'IND'    | 'CV-15G0MZ00'(!)           = ''              | ''                 | 'CV-15G0MZ00'              |'L_MMD-10DZ-1R5M-X1Q'| '1.5UH/16A'                    | 'DISCRETE' | 'IND SMD 1.5UH+-20%16A(MMD-10DZ-1R5M-X1Q)'      | 'CHIP'         | ''          | ''   | '20150429'  
 '1.5UH/16A'                    | 'SMLF'     | 'EMPTY'  | 'CV-15G0MZ00'(!)           = ''              | ''                 | 'CV-15G0MZ00'              |'L_MMD-10DZ-1R5M-X1Q'| 'NA'                           | 'IO'       | 'IND SMD 1.5UH+-20%16A(MMD-10DZ-1R5M-X1Q)'      | 'CHIP'         | ''          | ''   | '20150429'  
 '180NH/85A'                    | 'SMLF'     | 'IND'    | 'CV+18^0KZ04'(!)           = ''              | ''                 | 'CV+18^0KZ04'              |'L_HCUV106411-401G'| '180NH/85A'                    | 'DISCRETE' | 'IND SMD 180NH +-10% 85A(HCUV106411-181)'       | 'CHIP'         | ''          | ''   | '20150528'  
 '180NH/85A'                    | 'SMLF'     | 'EMPTY'  | 'CV+18^0KZ04'(!)           = ''              | ''                 | 'CV+18^0KZ04'              |'L_HCUV106411-401G'| 'NA'                           | 'IO'       | 'IND SMD 180NH +-10% 85A(HCUV106411-181)'       | 'CHIP'         | ''          | ''   | '20150528'  
 '200NH/76A'                    | 'SMLF'     | 'IND'    | 'CV+20^0KZ02'(!)           = ''              | ''                 | 'CV+20^0KZ02'              |'L_HCUV106411-401G'| '200NH/76A'                    | 'DISCRETE' | 'IND SMD 200NH +-10% 76A(HCUV106411-201)'       | 'CHIP'         | ''          | ''   | '20150528'  
 '200NH/76A'                    | 'SMLF'     | 'EMPTY'  | 'CV+20^0KZ02'(!)           = ''              | ''                 | 'CV+20^0KZ02'              |'L_HCUV106411-401G'| 'NA'                           | 'IO'       | 'IND SMD 200NH +-10% 76A(HCUV106411-201)'       | 'CHIP'         | ''          | ''   | '20150528'  
 '220NH/69A'                    | 'SMLF'     | 'IND'    | 'CV+22^0KZ14'(!)           = ''              | ''                 | 'CV+22^0KZ14'              |'L_HCUV106411-401G'| '220NH/69A'                    | 'DISCRETE' | 'IND SMD 220NH +-10% 69A(HCUV106411-221)'       | 'CHIP'         | ''          | ''   | '20150528'  
 '220NH/69A'                    | 'SMLF'     | 'EMPTY'  | 'CV+22^0KZ14'(!)           = ''              | ''                 | 'CV+22^0KZ14'              |'L_HCUV106411-401G'| 'NA'                           | 'IO'       | 'IND SMD 220NH +-10% 69A(HCUV106411-221)'       | 'CHIP'         | ''          | ''   | '20150528'  
 '220NH/75A'                    | 'SMLF'     | 'IND'    | 'CV+22^0KZ16'(!)           = 'End of Design' | 'Comp-Approve'     | 'CV+22^0KZ16'              |'L_HCUVE117512D'| '220NH/75A'                    | 'DISCRETE' | 'IND SMD 220NH 10% 75A(HCUVE117512D-221)'       | 'CHIP'         | ''          | ''   | '20150702'  
 '220NH/75A'                    | 'SMLF'     | 'EMPTY'  | 'CV+22^0KZ16'(!)           = 'End of Design' | 'Comp-Approve'     | 'CV+22^0KZ16'              |'L_HCUVE117512D'| 'NA'                           | 'IO'       | 'IND SMD 220NH 10% 75A(HCUVE117512D-221)'       | 'CHIP'         | ''          | ''   | '20150702'  
 '250NH/66A'                    | 'SMLF'     | 'IND'    | 'CV+25^0KZ03'(!)           = 'End of Design' | 'Comp-Approve'     | 'CV+25^0KZ03'              |'L_HCUVE117512D'| '250NH/66A'                    | 'DISCRETE' | 'IND SMD 250NH 10% 66A(HCUVE117512D-251)'       | 'CHIP'         | ''          | ''   | '20150702'  
 '250NH/66A'                    | 'SMLF'     | 'EMPTY'  | 'CV+25^0KZ03'(!)           = 'End of Design' | 'Comp-Approve'     | 'CV+25^0KZ03'              |'L_HCUVE117512D'| 'NA'                           | 'IO'       | 'IND SMD 250NH 10% 66A(HCUVE117512D-251)'       | 'CHIP'         | ''          | ''   | '20150702'  
 '270NH/60A'                    | 'SMLF'     | 'IND'    | 'CV+27^0KZ13'(!)           = 'End of Design' | 'Comp-Approve'     | 'CV+27^0KZ13'              |'L_HCUVE117512D'| '270NH/60A'                    | 'DISCRETE' | 'IND SMD 270NH 10% 60A(HCUVE117512D-271)'       | 'CHIP'         | ''          | ''   | '20150702'  
 '270NH/60A'                    | 'SMLF'     | 'EMPTY'  | 'CV+27^0KZ13'(!)           = 'End of Design' | 'Comp-Approve'     | 'CV+27^0KZ13'              |'L_HCUVE117512D'| 'NA'                           | 'IO'       | 'IND SMD 270NH 10% 60A(HCUVE117512D-271)'       | 'CHIP'         | ''          | ''   | '20150702'  
 '320NH/51A'                    | 'SMLF'     | 'IND'    | 'CV+32^0KZ09'(!)           = 'End of Design' | 'Comp-Approve'     | 'CV+32^0KZ09'              |'L_HCUVE117512D'| '320NH/51A'                    | 'DISCRETE' | 'IND SMD 320NH 10% 51A(HCUVE117512D-321)'       | 'CHIP'         | ''          | ''   | '20150702'  
 '320NH/51A'                    | 'SMLF'     | 'EMPTY'  | 'CV+32^0KZ09'(!)           = 'End of Design' | 'Comp-Approve'     | 'CV+32^0KZ09'              |'L_HCUVE117512D'| 'NA'                           | 'IO'       | 'IND SMD 320NH 10% 51A(HCUVE117512D-321)'       | 'CHIP'         | ''          | ''   | '20150702'  
 '400NH/41A'                    | 'SMLF'     | 'IND'    | 'CV+40^0KZ01'(!)           = 'End of Design' | 'Comp-Approve'     | 'CV+40^0KZ01'              |'L_HCUVE117512D'| '400NH/41A'                    | 'DISCRETE' | 'IND SMD 400NH 10% 41A(HCUVE117512D-401)'       | 'CHIP'         | ''          | ''   | '20150702'  
 '400NH/41A'                    | 'SMLF'     | 'EMPTY'  | 'CV+40^0KZ01'(!)           = 'End of Design' | 'Comp-Approve'     | 'CV+40^0KZ01'              |'L_HCUVE117512D'| 'NA'                           | 'IO'       | 'IND SMD 400NH 10% 41A(HCUVE117512D-401)'       | 'CHIP'         | ''          | ''   | '20150702'  
 '470NH/34A'                    | 'SMLF'     | 'IND'    | 'CV+47Z0KZ00'(!)           = 'End of Design' | 'Comp-Approve'     | 'CV+47Z0KZ00'              |'L_HCUVE117512D'| '470NH/34A'                    | 'DISCRETE' | 'IND SMD 470NH 10% 34A(HCUVE117512D-471)'       | 'CHIP'         | ''          | ''   | '20150702'  
 '470NH/34A'                    | 'SMLF'     | 'EMPTY'  | 'CV+47Z0KZ00'(!)           = 'End of Design' | 'Comp-Approve'     | 'CV+47Z0KZ00'              |'L_HCUVE117512D'| 'NA'                           | 'IO'       | 'IND SMD 470NH 10% 34A(HCUVE117512D-471)'       | 'CHIP'         | ''          | ''   | '20150702'  
 '600NH/24.5A'                  | 'SMLF'     | 'IND'    | 'CV+60Q0KZ00'(!)           = ''              | ''                 | 'CV+60Q0KZ00'              |'L_HCUVE117512D'| '600NH/24.5A'                  | 'DISCRETE' | 'IND SMD 600N 10% 24.5A(HCUVE117512D-601)'      | 'CHIP'         | ''          | ''   | '20150702'  
 '600NH/24.5A'                  | 'SMLF'     | 'EMPTY'  | 'CV+60Q0KZ00'(!)           = ''              | ''                 | 'CV+60Q0KZ00'              |'L_HCUVE117512D'| 'NA'                           | 'IO'       | 'IND SMD 600N 10% 24.5A(HCUVE117512D-601)'      | 'CHIP'         | ''          | ''   | '20150702'  
 '100NH/42A'                    | 'SMLF'     | 'IND'    | 'CV+10^0MZ10'(!)           = ''              | ''                 | 'CV+10^0MZ10'              |'L_HCUVE756257_7X5-7'| '100NH/42A'                    | 'DISCRETE' | 'IND SMD 100NH 20% 42A(HCUVE756257-101)'        | 'CHIP'         | ''          | ''   | '20150703'  
 '100NH/42A'                    | 'SMLF'     | 'EMPTY'  | 'CV+10^0MZ10'(!)           = ''              | ''                 | 'CV+10^0MZ10'              |'L_HCUVE756257_7X5-7'| 'NA'                           | 'IO'       | 'IND SMD 100NH 20% 42A(HCUVE756257-101)'        | 'CHIP'         | ''          | ''   | '20150703'  
 '0.22UH/15A'                   | 'SMLF'     | 'IND'    | 'CV+22F0MZ00'(!)           = ''              | ''                 | 'CV+22F0MZ00'              |'L_CMLS041B_4-4X4-2'| '0.22UH/15A'                   | 'DISCRETE' | 'IND SMD 0.22UH +-20% 15A(CMLS041B-R22MS)'      | 'CHIP'         | ''          | ''   | '20150707'  
 '0.22UH/15A'                   | 'SMLF'     | 'EMPTY'  | 'CV+22F0MZ00'(!)           = ''              | ''                 | 'CV+22F0MZ00'              |'L_CMLS041B_4-4X4-2'| 'NA'                           | 'IO'       | 'IND SMD 0.22UH +-20% 15A(CMLS041B-R22MS)'      | 'CHIP'         | ''          | ''   | '20150707'  
 '0.36UH/24A'                   | 'SMLF'     | 'IND'    | 'CV+36P0MZ01'(!)           = ''              | ''                 | 'CV+36P0MZ01'              |'L_PCME064T-R36MS1R407'| '0.36UH/24A'                   | 'DISCRETE' | 'IND SMD 0.36UH20%24A PCME064T-R36MS1R407'      | 'CHIP'         | ''          | ''   | '20150708'  
 '0.36UH/24A'                   | 'SMLF'     | 'EMPTY'  | 'CV+36P0MZ01'(!)           = ''              | ''                 | 'CV+36P0MZ01'              |'L_PCME064T-R36MS1R407'| 'NA'                           | 'IO'       | 'IND SMD 0.36UH20%24A PCME064T-R36MS1R407'      | 'CHIP'         | ''          | ''   | '20150708'  
 '0.22UH/13A'                   | 'SMLF'     | 'IND'    | 'CV+22D0MZ00'(!)           = ''              | ''                 | 'CV+22D0MZ00'              |'L_MMD-04BZ-1R5M-X2'| '0.22UH/13A'                   | 'DISCRETE' | 'IND SMD 0.22UH20%13A(MMD-04BZ-R22M-V1Q)'       | 'CHIP'         | ''          | ''   | '20150713'  
 '0.22UH/13A'                   | 'SMLF'     | 'EMPTY'  | 'CV+22D0MZ00'(!)           = ''              | ''                 | 'CV+22D0MZ00'              |'L_MMD-04BZ-1R5M-X2'| 'NA'                           | 'IO'       | 'IND SMD 0.22UH20%13A(MMD-04BZ-R22M-V1Q)'       | 'CHIP'         | ''          | ''   | '20150713'  
 '5.6NH/760MA'                  | 'SMLF'     | 'IND'    | 'CVB5608JZ00'(!)           = ''              | ''                 | 'CVB5608JZ00'              |'L0402CS'| '5.6NH/760MA'                  | 'DISCRETE' | 'IND SMD 5.6N 5% 760MA(CS0402-5N6J-S)'          | 'CHIP'         | ''          | ''   | '20150713'  
 '5.6NH/760MA'                  | 'SMLF'     | 'EMPTY'  | 'CVB5608JZ00'(!)           = ''              | ''                 | 'CVB5608JZ00'              |'L0402CS'| 'NA'                           | 'IO'       | 'IND SMD 5.6N 5% 760MA(CS0402-5N6J-S)'          | 'CHIP'         | ''          | ''   | '20150713'  
 '100NH/16A'                    | 'SMLF'     | 'IND'    | 'CV+10G0MZ04'(!)           = ''              | ''                 | 'CV+10G0MZ04'              |'L_HCBS4545_4-5X4-5'| '100NH/16A'                    | 'DISCRETE' | 'IND SMD 100NH 20% 16A(HCBS4545-101)'           | 'CHIP'         | ''          | ''   | '20150715'  
 '100NH/16A'                    | 'SMLF'     | 'EMPTY'  | 'CV+10G0MZ04'(!)           = ''              | ''                 | 'CV+10G0MZ04'              |'L_HCBS4545_4-5X4-5'| 'NA'                           | 'IO'       | 'IND SMD 100NH 20% 16A(HCBS4545-101)'           | 'CHIP'         | ''          | ''   | '20150715'  
 '70NH/60A'                     | 'SMLF'     | 'IND'    | 'CVA70^0MZ00'(!)           = 'End of Design' | 'Comp-Approve'     | 'CVA70^0MZ00'              |'L_HCBS6170_6-1X6'| '70NH/60A'                     | 'DISCRETE' | 'IND SMD 70NH 20% 60A(HCBS6170-700)'            | 'CHIP'         | ''          | ''   | '20150715'  
 '70NH/60A'                     | 'SMLF'     | 'EMPTY'  | 'CVA70^0MZ00'(!)           = 'End of Design' | 'Comp-Approve'     | 'CVA70^0MZ00'              |'L_HCBS6170_6-1X6'| 'NA'                           | 'IO'       | 'IND SMD 70NH 20% 60A(HCBS6170-700)'            | 'CHIP'         | ''          | ''   | '20150715'  
 '0.22UH/13A'                   | 'SMLF'     | 'IND'    | 'CV+22D0MZ02'(!)           = ''              | ''                 | 'CV+22D0MZ02'              |'L_CMMS042T_4-4X4-2'| '0.22UH/13A'                   | 'DISCRETE' | 'IND SMD 0.22UH 20% 13A(CMMS042T-R22MS)'        | 'CHIP'         | ''          | ''   | '20150724'  
 '0.22UH/13A'                   | 'SMLF'     | 'EMPTY'  | 'CV+22D0MZ02'(!)           = ''              | ''                 | 'CV+22D0MZ02'              |'L_CMMS042T_4-4X4-2'| 'NA'                           | 'IO'       | 'IND SMD 0.22UH 20% 13A(CMMS042T-R22MS)'        | 'CHIP'         | ''          | ''   | '20150724'  
 '0.24UH/4.8A'                  | 'SMLF'     | 'IND'    | 'CV+2448TZ00'(!)           = ''              | 'End of Life'      | 'CV+2448TZ00'              |'L_MLV-TP10NR24N-XP_2X1-6_EOL'| '0.24UH/4.8A'                  | 'DISCRETE' | 'IND SMD 0.24UH 30% 4.8A(MLV-TP10NR24N-XP'      | 'CHIP'         | ''          | ''   | '20150729'  
 '0.24UH/4.8A'                  | 'SMLF'     | 'EMPTY'  | 'CV+2448TZ00'(!)           = ''              | 'End of Life'      | 'CV+2448TZ00'              |'L_MLV-TP10NR24N-XP_2X1-6_EOL'| 'NA'                           | 'IO'       | 'IND SMD 0.24UH 30% 4.8A(MLV-TP10NR24N-XP'      | 'CHIP'         | ''          | ''   | '20150729'  
 '0.36UH/24A'                   | 'SMLF'     | 'IND'    | 'CV+36P0MZ02'(!)           = ''              | ''                 | 'CV+36P0MZ02'              |'L_MMD-06DZ'| '0.36UH/24A'                   | 'DISCRETE' | 'IND SMD 0.36UH 20% 24A(MMD-06DZER36MGX5Q'      | 'CHIP'         | ''          | ''   | '20150730'  
 '0.36UH/24A'                   | 'SMLF'     | 'EMPTY'  | 'CV+36P0MZ02'(!)           = ''              | ''                 | 'CV+36P0MZ02'              |'L_MMD-06DZ'| 'NA'                           | 'IO'       | 'IND SMD 0.36UH 20% 24A(MMD-06DZER36MGX5Q'      | 'CHIP'         | ''          | ''   | '20150730'  
 '68NH/0.3A'                    | 'SMLF'     | 'IND'    | 'CVA6803MZ00'(!)           = ''              | ''                 | 'CVA6803MZ00'              |'L0805'| '68NH/0.3A'                    | 'DISCRETE' | 'IND SMD 68NH 20% 0.3A(MLF2012D68NMT)'          | 'CHIP'         | ''          | ''   | '20150814'  
 '68NH/0.3A'                    | 'SMLF'     | 'EMPTY'  | 'CVA6803MZ00'(!)           = ''              | ''                 | 'CVA6803MZ00'              |'L0805'| 'NA'                           | 'IO'       | 'IND SMD 68NH 20% 0.3A(MLF2012D68NMT)'          | 'CHIP'         | ''          | ''   | '20150814'  
 '0.56UH/18A'                   | 'SMLF'     | 'IND'    | 'CV+56I0MZ02'(!)           = ''              | ''                 | 'CV+56I0MZ02'              |'L_PCMB065T'| '0.56UH/18A'                   | 'DISCRETE' | 'IND SMD 0.56UH +-20% 18A(PIMB065T-R56MS)'      | 'CHIP'         | ''          | ''   | '20150907'  
 '0.56UH/18A'                   | 'SMLF'     | 'EMPTY'  | 'CV+56I0MZ02'(!)           = ''              | ''                 | 'CV+56I0MZ02'              |'L_PCMB065T'| 'NA'                           | 'IO'       | 'IND SMD 0.56UH +-20% 18A(PIMB065T-R56MS)'      | 'CHIP'         | ''          | ''   | '20150907'  
 '47NH/0.3A'                    | 'SMLF'     | 'IND'    | 'CVA4703JN03'(!)           = ''              | ''                 | 'CVA4703JN03'              |'L0603'| '47NH/0.3A'                    | 'DISCRETE' | 'IND SMD 47NH 5% 0.3A(LQG18HN47NJ00D)'          | 'CHIP'         | ''          | ''   | '20150916'  
 '47NH/0.3A'                    | 'SMLF'     | 'EMPTY'  | 'CVA4703JN03'(!)           = ''              | ''                 | 'CVA4703JN03'              |'L0603'| 'NA'                           | 'IO'       | 'IND SMD 47NH 5% 0.3A(LQG18HN47NJ00D)'          | 'CHIP'         | ''          | ''   | '20150916'  
 '0.56UH/25A'                   | 'SMLF'     | 'IND'    | 'CV+56Q0MZ03'(!)           = ''              | ''                 | 'CV+56Q0MZ03'              |'L_PCMC104T'| '0.56UH/25A'                   | 'DISCRETE' | 'IND SMD 0.56U +-20% 25A(PCMC104T-R56MN)'       | 'CHIP'         | ''          | ''   | '20151007'  
 '0.56UH/25A'                   | 'SMLF'     | 'EMPTY'  | 'CV+56Q0MZ03'(!)           = ''              | ''                 | 'CV+56Q0MZ03'              |'L_PCMC104T'| 'NA'                           | 'IO'       | 'IND SMD 0.56U +-20% 25A(PCMC104T-R56MN)'       | 'CHIP'         | ''          | ''   | '20151007'  
 'SBY100505T-121Y-NA/500MA'     | 'SMLF'     | 'IND'    | 'CX05T121002'(!)           = ''              | ''                 | 'CX05T121002'              |'L0402'| 'SBY100505T-121Y-NA/500MA'     | 'DISCRETE' | 'EMI FILTER SBY100505T-121Y-NA(120,500MA)'      | 'CHIP'         | ''          | ''   | '20151015'  
 'SBY100505T-121Y-NA/500MA'     | 'SMLF'     | 'EMPTY'  | 'CX05T121002'(!)           = ''              | ''                 | 'CX05T121002'              |'L0402'| 'NA'                           | 'IO'       | 'EMI FILTER SBY100505T-121Y-NA(120,500MA)'      | 'CHIP'         | ''          | ''   | '20151015'  
 'MMZ2012S601AT/500MA'          | 'SMLF'     | 'IND'    | 'CX12S601003'(!)           = 'End of Design' | 'End of Life'      | 'CX12S601003'              |'L0805_EOL'| 'MMZ2012S601AT/500MA'          | 'DISCRETE' | 'EMI FIL,MMZ2012S601AT,500MA,2012,600/OHM'      | 'CHIP'         | ''          | ''   | '20151029'  
 'MMZ2012S601AT/500MA'          | 'SMLF'     | 'EMPTY'  | 'CX12S601003'(!)           = 'End of Design' | 'End of Life'      | 'CX12S601003'              |'L0805_EOL'| 'NA'                           | 'IO'       | 'EMI FIL,MMZ2012S601AT,500MA,2012,600/OHM'      | 'CHIP'         | ''          | ''   | '20151029'  
 '250NH/38A'                    | 'SMLF'     | 'IND'    | 'CV+25^0KZ04'(!)           = ''              | ''                 | 'CV+25^0KZ04'              |'L_HCUVD6270_6-2X5-5'| '250NH/38A'                    | 'DISCRETE' | 'IND SMD 250NH 10% 38A(HCUVD6270-251LY)'        | 'CHIP'         | ''          | ''   | '20151029'  
 '250NH/38A'                    | 'SMLF'     | 'EMPTY'  | 'CV+25^0KZ04'(!)           = ''              | ''                 | 'CV+25^0KZ04'              |'L_HCUVD6270_6-2X5-5'| 'NA'                           | 'IO'       | 'IND SMD 250NH 10% 38A(HCUVD6270-251LY)'        | 'CHIP'         | ''          | ''   | '20151029'  
 '1UH/17A'                      | 'SMLF'     | 'IND'    | 'CV-10H0KZ00'(!)           = ''              | ''                 | 'CV-10H0KZ00'              |'L_HCUVD8095D-102QL_8X8'| '1UH/17A'                      | 'DISCRETE' | 'IND SMD 1UH 10% 17A(HCUVD8095D-102QL)'         | 'CHIP'         | ''          | ''   | '20151104'  
 '1UH/17A'                      | 'SMLF'     | 'EMPTY'  | 'CV-10H0KZ00'(!)           = ''              | ''                 | 'CV-10H0KZ00'              |'L_HCUVD8095D-102QL_8X8'| 'NA'                           | 'IO'       | 'IND SMD 1UH 10% 17A(HCUVD8095D-102QL)'         | 'CHIP'         | ''          | ''   | '20151104'  
 '1000NH/19A'                   | 'SMLF'     | 'IND'    | 'CV-10J0KZ00'(!)           = ''              | ''                 | 'CV-10J0KZ00'              |'L_HCUVD8095D-102QL_8X8'| '1000NH/19A'                   | 'DISCRETE' | 'IND SMD 1000NH 10% 19A(HCUVD8095-102QL)'       | 'CHIP'         | ''          | ''   | '20151104'  
 '1000NH/19A'                   | 'SMLF'     | 'EMPTY'  | 'CV-10J0KZ00'(!)           = ''              | ''                 | 'CV-10J0KZ00'              |'L_HCUVD8095D-102QL_8X8'| 'NA'                           | 'IO'       | 'IND SMD 1000NH 10% 19A(HCUVD8095-102QL)'       | 'CHIP'         | ''          | ''   | '20151104'  
 '0.6UH/18A'                    | 'SMLF'     | 'IND'    | 'CV+60I0KZ00'(!)           = ''              | 'End of Life'      | 'CV+60I0KZ00'              |'L_HCUVD6595D-601LY_6-5X6-5_EOL'| '0.6UH/18A'                    | 'DISCRETE' | 'IND SMD 0.6UH 10% 18A(HCUVD6595D-601LY)'       | 'CHIP'         | ''          | ''   | '20151104'  
 '0.6UH/18A'                    | 'SMLF'     | 'EMPTY'  | 'CV+60I0KZ00'(!)           = ''              | 'End of Life'      | 'CV+60I0KZ00'              |'L_HCUVD6595D-601LY_6-5X6-5_EOL'| 'NA'                           | 'IO'       | 'IND SMD 0.6UH 10% 18A(HCUVD6595D-601LY)'       | 'CHIP'         | ''          | ''   | '20151104'  
 '600NH/20A'                    | 'SMLF'     | 'IND'    | 'CV+60K0KZ00'(!)           = ''              | ''                 | 'CV+60K0KZ00'              |'L_HCUVD6595D-601LY_6-5X6-5'| '600NH/20A'                    | 'DISCRETE' | 'IND SMD 600NH 10% 20A(HCUVD6595-601LY)'        | 'CHIP'         | ''          | ''   | '20151104'  
 '600NH/20A'                    | 'SMLF'     | 'EMPTY'  | 'CV+60K0KZ00'(!)           = ''              | ''                 | 'CV+60K0KZ00'              |'L_HCUVD6595D-601LY_6-5X6-5'| 'NA'                           | 'IO'       | 'IND SMD 600NH 10% 20A(HCUVD6595-601LY)'        | 'CHIP'         | ''          | ''   | '20151104'  
 '1000NH/12A'                   | 'SMLF'     | 'IND'    | 'CV-10C0KZ00'(!)           = ''              | ''                 | 'CV-10C0KZ00'              |'L_HCUVD6595D-601LY_6-5X6-5'| '1000NH/12A'                   | 'DISCRETE' | 'IND SMD 1000NH 10% 12A(HCUVD6595-102LY)'       | 'CHIP'         | ''          | ''   | '20151104'  
 '1000NH/12A'                   | 'SMLF'     | 'EMPTY'  | 'CV-10C0KZ00'(!)           = ''              | ''                 | 'CV-10C0KZ00'              |'L_HCUVD6595D-601LY_6-5X6-5'| 'NA'                           | 'IO'       | 'IND SMD 1000NH 10% 12A(HCUVD6595-102LY)'       | 'CHIP'         | ''          | ''   | '20151104'  
 '0.1U/7A'                      | 'SMLF'     | 'IND'    | 'CV+1070TZ00'(!)           = ''              | ''                 | 'CV+1070TZ00'              |'L_MLV-YT12N_2-5X2'| '0.1U/7A'                      | 'DISCRETE' | 'IND SMD 0.1U 30% 7A(MLV-YT12NR10N-M3Q)'        | 'CHIP'         | ''          | ''   | '20151116'  
 '0.1U/7A'                      | 'SMLF'     | 'EMPTY'  | 'CV+1070TZ00'(!)           = ''              | ''                 | 'CV+1070TZ00'              |'L_MLV-YT12N_2-5X2'| 'NA'                           | 'IO'       | 'IND SMD 0.1U 30% 7A(MLV-YT12NR10N-M3Q)'        | 'CHIP'         | ''          | ''   | '20151116'  
 '0.24U/4.7A'                   | 'SMLF'     | 'IND'    | 'CV+2447TZ00'(!)           = ''              | ''                 | 'CV+2447TZ00'              |'L_MLV-TP10NR24N-XP_2X1-6'| '0.24U/4.7A'                   | 'DISCRETE' | 'INDSMD 0.24U 30% 4.7A(MLV-TP10NR24N-P4Q'       | 'CHIP'         | ''          | ''   | '20151116'  
 '0.24U/4.7A'                   | 'SMLF'     | 'EMPTY'  | 'CV+2447TZ00'(!)           = ''              | ''                 | 'CV+2447TZ00'              |'L_MLV-TP10NR24N-XP_2X1-6'| 'NA'                           | 'IO'       | 'INDSMD 0.24U 30% 4.7A(MLV-TP10NR24N-P4Q'       | 'CHIP'         | ''          | ''   | '20151116'  
 '35F0121-0SR-10'               | 'SMLF'     | 'IND'    | 'TMP_QCX0F0121000'(!)      = ''              | ''                 | 'CX0F0121000'              |'L_35F0121'| '35F0121-0SR-10 '              | 'DISCRETE' | 'EMI FILTER 35F0121-0SR-10 (42.10A)'            | 'CHIP'         | ''          | ''   | '20151119'  
 '35F0121-0SR-10'               | 'SMLF'     | 'EMPTY'  | 'TMP_QCX0F0121000'(!)      = ''              | ''                 | 'CX0F0121000'              |'L_35F0121'| 'NA'                           | 'IO'       | 'EMI FILTER 35F0121-0SR-10 (42.10A)'            | 'CHIP'         | ''          | ''   | '20151119'  
 '1UH/11A'                      | 'SMLF'     | 'IND'    | 'CV-10B0KZ00'(!)           = ''              | 'End of Life'      | 'CV-10B0KZ00'              |'L_HCUVD6595D-601LY_6-5X6-5_EOL'| '1UH/11A'                      | 'DISCRETE' | 'IND SMD 1UH +-10% 11A(HCUVD6595D-102LY)'       | 'CHIP'         | ''          | ''   | '20151120'  
 '1UH/11A'                      | 'SMLF'     | 'EMPTY'  | 'CV-10B0KZ00'(!)           = ''              | 'End of Life'      | 'CV-10B0KZ00'              |'L_HCUVD6595D-601LY_6-5X6-5_EOL'| 'NA'                           | 'IO'       | 'IND SMD 1UH +-10% 11A(HCUVD6595D-102LY)'       | 'CHIP'         | ''          | ''   | '20151120'  
 '560NH/32A'                    | 'SMLF'     | 'IND'    | 'CV+56X0KZ00'(!)           = ''              | ''                 | 'CV+56X0KZ00'              |'L_HCUVD8083_8X8'| '560NH/32A'                    | 'DISCRETE' | 'IND SMD 560NH 10% 32A(HCUVD8083-561H)'         | 'CHIP'         | ''          | ''   | '20151126'  
 '560NH/32A'                    | 'SMLF'     | 'EMPTY'  | 'CV+56X0KZ00'(!)           = ''              | ''                 | 'CV+56X0KZ00'              |'L_HCUVD8083_8X8'| 'NA'                           | 'IO'       | 'IND SMD 560NH 10% 32A(HCUVD8083-561H)'         | 'CHIP'         | ''          | ''   | '20151126'  
 '940NH/19A'                    | 'SMLF'     | 'IND'    | 'CV+94J0KZ00'(!)           = ''              | ''                 | 'CV+94J0KZ00'              |'L_HCUVD8083_8X8'| '940NH/19A'                    | 'DISCRETE' | 'IND SMD 940NH 10% 19A(HCUVD8083-941H)'         | 'CHIP'         | ''          | ''   | '20151126'  
 '940NH/19A'                    | 'SMLF'     | 'EMPTY'  | 'CV+94J0KZ00'(!)           = ''              | ''                 | 'CV+94J0KZ00'              |'L_HCUVD8083_8X8'| 'NA'                           | 'IO'       | 'IND SMD 940NH 10% 19A(HCUVD8083-941H)'         | 'CHIP'         | ''          | ''   | '20151126'  
 '100NH/80MA'                   | 'SMLF'     | 'IND'    | 'CV+1001JN01'(!)           = ''              | ''                 | 'CV+1001JN01'              |'L0201'| '100NH/80MA'                   | 'DISCRETE' | 'IND CHIP 100N +-5% 80MA LQP03TNR10J02D'        | 'CHIP'         | ''          | ''   | '20151130'  
 '100NH/80MA'                   | 'SMLF'     | 'EMPTY'  | 'CV+1001JN01'(!)           = ''              | ''                 | 'CV+1001JN01'              |'L0201'| 'NA'                           | 'IO'       | 'IND CHIP 100N +-5% 80MA LQP03TNR10J02D'        | 'CHIP'         | ''          | ''   | '20151130'  
 '120NH/40MA'                   | 'SMLF'     | 'IND'    | 'CV+1201JN01'(!)           = ''              | ''                 | 'CV+1201JN01'              |'L0201'| '120NH/40MA'                   | 'DISCRETE' | 'IND CHIP 120N+-5% 40MA LQP03TNR12J02D'         | 'CHIP'         | ''          | ''   | '20151130'  
 '120NH/40MA'                   | 'SMLF'     | 'EMPTY'  | 'CV+1201JN01'(!)           = ''              | ''                 | 'CV+1201JN01'              |'L0201'| 'NA'                           | 'IO'       | 'IND CHIP 120N+-5% 40MA LQP03TNR12J02D'         | 'CHIP'         | ''          | ''   | '20151130'  
 '33NH/120MA'                   | 'SMLF'     | 'IND'    | 'CVA3302JN05'(!)           = ''              | ''                 | 'CVA3302JN05'              |'L0201'| '33NH/120MA'                   | 'DISCRETE' | 'IND CHIP 33N +-5%,120MA(LQP03TN33NJ02D)'       | 'CHIP'         | ''          | ''   | '20151130'  
 '33NH/120MA'                   | 'SMLF'     | 'EMPTY'  | 'CVA3302JN05'(!)           = ''              | ''                 | 'CVA3302JN05'              |'L0201'| 'NA'                           | 'IO'       | 'IND CHIP 33N +-5%,120MA(LQP03TN33NJ02D)'       | 'CHIP'         | ''          | ''   | '20151130'  
 '39NH/120MA'                   | 'SMLF'     | 'IND'    | 'CVA3902JN01'(!)           = ''              | ''                 | 'CVA3902JN01'              |'L0201'| '39NH/120MA'                   | 'DISCRETE' | 'IND CHIP 39N(+-5%,120MA)LQP03TN39NJ02D'        | 'CHIP'         | ''          | ''   | '20151130'  
 '39NH/120MA'                   | 'SMLF'     | 'EMPTY'  | 'CVA3902JN01'(!)           = ''              | ''                 | 'CVA3902JN01'              |'L0201'| 'NA'                           | 'IO'       | 'IND CHIP 39N(+-5%,120MA)LQP03TN39NJ02D'        | 'CHIP'         | ''          | ''   | '20151130'  
 '1NH/750MA'                    | 'SMLF'     | 'IND'    | 'CVB1008TN00'(!)           = ''              | ''                 | 'CVB1008TN00'              |'L0201'| '1NH/750MA'                    | 'DISCRETE' | 'IND CHIP 1NH(+-0.1NH,750MA)LQP03TN1N0B02'      | 'CHIP'         | ''          | ''   | '20151130'  
 '1NH/750MA'                    | 'SMLF'     | 'EMPTY'  | 'CVB1008TN00'(!)           = ''              | ''                 | 'CVB1008TN00'              |'L0201'| 'NA'                           | 'IO'       | 'IND CHIP 1NH(+-0.1NH,750MA)LQP03TN1N0B02'      | 'CHIP'         | ''          | ''   | '20151130'  
 '3NH/450MA'                    | 'SMLF'     | 'IND'    | 'CVB3005BN00'(!)           = ''              | ''                 | 'CVB3005BN00'              |'L0201'| '3NH/450MA'                    | 'DISCRETE' | 'IND CHIP 3N(+-0.1N,450MA)LQP03TN3N0B02D'       | 'CHIP'         | ''          | ''   | '20151130'  
 '3NH/450MA'                    | 'SMLF'     | 'EMPTY'  | 'CVB3005BN00'(!)           = ''              | ''                 | 'CVB3005BN00'              |'L0201'| 'NA'                           | 'IO'       | 'IND CHIP 3N(+-0.1N,450MA)LQP03TN3N0B02D'       | 'CHIP'         | ''          | ''   | '20151130'  
 '100NH/0.15A'                  | 'SMLF'     | 'IND'    | 'CV+1002JN00'(!)           = ''              | ''                 | 'CV+1002JN00'              |'L0402'| '100NH/0.15A'                  | 'DISCRETE' | 'IND CHIP 100N(+-5%,0.15A)LQG15HNR10J02D'       | 'CHIP'         | ''          | ''   | '20151202'  
 '100NH/0.15A'                  | 'SMLF'     | 'EMPTY'  | 'CV+1002JN00'(!)           = ''              | ''                 | 'CV+1002JN00'              |'L0402'| 'NA'                           | 'IO'       | 'IND CHIP 100N(+-5%,0.15A)LQG15HNR10J02D'       | 'CHIP'         | ''          | ''   | '20151202'  
 '1NH/0.3A'                     | 'SMLF'     | 'IND'    | 'CVB1003TN00'(!)           = ''              | ''                 | 'CVB1003TN00'              |'L0402'| '1NH/0.3A'                     | 'DISCRETE' | 'IND CHIP 1N(+-0.3NH,0.3A)LQG15HN1N0S02D'       | 'CHIP'         | ''          | ''   | '20151202'  
 '1NH/0.3A'                     | 'SMLF'     | 'EMPTY'  | 'CVB1003TN00'(!)           = ''              | ''                 | 'CVB1003TN00'              |'L0402'| 'NA'                           | 'IO'       | 'IND CHIP 1N(+-0.3NH,0.3A)LQG15HN1N0S02D'       | 'CHIP'         | ''          | ''   | '20151202'  
 '3NH/300MA'                    | 'SMLF'     | 'IND'    | 'CVB3003TN00'(!)           = ''              | ''                 | 'CVB3003TN00'              |'L0402'| '3NH/300MA'                    | 'DISCRETE' | 'IND CHIP 3NH,+-0.3N,300MA,LQG15HN3N0S02D'      | 'CHIP'         | ''          | ''   | '20151202'  
 '3NH/300MA'                    | 'SMLF'     | 'EMPTY'  | 'CVB3003TN00'(!)           = ''              | ''                 | 'CVB3003TN00'              |'L0402'| 'NA'                           | 'IO'       | 'IND CHIP 3NH,+-0.3N,300MA,LQG15HN3N0S02D'      | 'CHIP'         | ''          | ''   | '20151202'  
 '120NH/150MA'                  | 'SMLF'     | 'IND'    | 'CV+1202JN00'(!)           = ''              | ''                 | 'CV+1202JN00'              |'L0402'| '120NH/150MA'                  | 'DISCRETE' | 'IND CHIP 120NH+-5%,150MA(LQG15HSR12J02D)'      | 'CHIP'         | ''          | ''   | '20151203'  
 '120NH/150MA'                  | 'SMLF'     | 'EMPTY'  | 'CV+1202JN00'(!)           = ''              | ''                 | 'CV+1202JN00'              |'L0402'| 'NA'                           | 'IO'       | 'IND CHIP 120NH+-5%,150MA(LQG15HSR12J02D)'      | 'CHIP'         | ''          | ''   | '20151203'  
 '33NH/200MA'                   | 'SMLF'     | 'IND'    | 'CVA3302JN11'(!)           = ''              | ''                 | 'CVA3302JN11'              |'L0402'| '33NH/200MA'                   | 'DISCRETE' | 'INDUCTOR CHIP 33NH +-5% 200MA,1005'            | 'CHIP'         | ''          | ''   | '20151203'  
 '33NH/200MA'                   | 'SMLF'     | 'EMPTY'  | 'CVA3302JN11'(!)           = ''              | ''                 | 'CVA3302JN11'              |'L0402'| 'NA'                           | 'IO'       | 'INDUCTOR CHIP 33NH +-5% 200MA,1005'            | 'CHIP'         | ''          | ''   | '20151203'  
 '39NH/0.2A'                    | 'SMLF'     | 'IND'    | 'CVA3902JN02'(!)           = ''              | ''                 | 'CVA3902JN02'              |'L0402'| '39NH/0.2A'                    | 'DISCRETE' | 'IND CHIP 39NH5%0.2A,LQG15HS39NJ02D PALAS'      | 'CHIP'         | ''          | ''   | '20151203'  
 '39NH/0.2A'                    | 'SMLF'     | 'EMPTY'  | 'CVA3902JN02'(!)           = ''              | ''                 | 'CVA3902JN02'              |'L0402'| 'NA'                           | 'IO'       | 'IND CHIP 39NH5%0.2A,LQG15HS39NJ02D PALAS'      | 'CHIP'         | ''          | ''   | '20151203'  
 '1UH/24A'                      | 'SMLF'     | 'IND'    | 'CV-10P0MZ03'(!)           = ''              | ''                 | 'CV-10P0MZ03'              |'L_MHD-07EZP_7-2X7-5'| '1UH/24A'                      | 'DISCRETE' | 'IND SMD 1UH 20% 24A(MHD-07EZP1R0M-XCQ)'        | 'CHIP'         | ''          | ''   | '20151209'  
 '1UH/24A'                      | 'SMLF'     | 'EMPTY'  | 'CV-10P0MZ03'(!)           = ''              | ''                 | 'CV-10P0MZ03'              |'L_MHD-07EZP_7-2X7-5'| 'NA'                           | 'IO'       | 'IND SMD 1UH 20% 24A(MHD-07EZP1R0M-XCQ)'        | 'CHIP'         | ''          | ''   | '20151209'  
 '220NH/81A'                    | 'SMLF'     | 'IND'    | 'CV+22^0KZ17'(!)           = 'End of Design' | 'Comp-Approve'     | 'CV+22^0KZ17'              |'L_SI2C100712_10-7X7-5'| '220NH/81A'                    | 'DISCRETE' | 'IND SMD 220NH 10% 81A(SI2C100712-R22K-R1'      | 'CHIP'         | ''          | ''   | '20151209'  
 '220NH/81A'                    | 'SMLF'     | 'EMPTY'  | 'CV+22^0KZ17'(!)           = 'End of Design' | 'Comp-Approve'     | 'CV+22^0KZ17'              |'L_SI2C100712_10-7X7-5'| 'NA'                           | 'IO'       | 'IND SMD 220NH 10% 81A(SI2C100712-R22K-R1'      | 'CHIP'         | ''          | ''   | '20151209'  
 '120NH/94A'                    | 'SMLF'     | 'IND'    | 'CV+12^0KZ05'(!)           = 'End of Design' | 'Comp-Approve'     | 'CV+12^0KZ05'              |'L_HCUVE966490D-121'| '120NH/94A'                    | 'DISCRETE' | 'IND SMD 120NH 10% 94A(HCUVE966490D-121)'       | 'CHIP'         | ''          | ''   | '20151221'  
 '120NH/94A'                    | 'SMLF'     | 'EMPTY'  | 'CV+12^0KZ05'(!)           = 'End of Design' | 'Comp-Approve'     | 'CV+12^0KZ05'              |'L_HCUVE966490D-121'| 'NA'                           | 'IO'       | 'IND SMD 120NH 10% 94A(HCUVE966490D-121)'       | 'CHIP'         | ''          | ''   | '20151221'  
 '150NH/75A'                    | 'SMLF'     | 'IND'    | 'CV+15^0KZ08'(!)           = 'End of Design' | 'Comp-Approve'     | 'CV+15^0KZ08'              |'L_HCUVE966490D-121'| '150NH/75A'                    | 'DISCRETE' | 'IND SMD 150NH 10% 75A(HCUVE966490D-151)'       | 'CHIP'         | ''          | ''   | '20151221'  
 '150NH/75A'                    | 'SMLF'     | 'EMPTY'  | 'CV+15^0KZ08'(!)           = 'End of Design' | 'Comp-Approve'     | 'CV+15^0KZ08'              |'L_HCUVE966490D-121'| 'NA'                           | 'IO'       | 'IND SMD 150NH 10% 75A(HCUVE966490D-151)'       | 'CHIP'         | ''          | ''   | '20151221'  
 '300NH/33A'                    | 'SMLF'     | 'IND'    | 'CV+30Y0KZ00'(!)           = 'End of Design' | 'Comp-Approve'     | 'CV+30Y0KZ00'              |'L_HCUVE966490D-121'| '300NH/33A'                    | 'DISCRETE' | 'IND SMD 300NH 10% 33A(HCUVE966490D-301)'       | 'CHIP'         | ''          | ''   | '20151221'  
 '300NH/33A'                    | 'SMLF'     | 'EMPTY'  | 'CV+30Y0KZ00'(!)           = 'End of Design' | 'Comp-Approve'     | 'CV+30Y0KZ00'              |'L_HCUVE966490D-121'| 'NA'                           | 'IO'       | 'IND SMD 300NH 10% 33A(HCUVE966490D-301)'       | 'CHIP'         | ''          | ''   | '20151221'  
 '0.22UH/53A'                   | 'SMLF'     | 'IND'    | 'CV+22^0MZ26'(!)           = ''              | ''                 | 'CV+22^0MZ26'              |'L_MMD12FD'| '0.22UH/53A'                   | 'DISCRETE' | 'IND SMD 0.22UH 20% 53A(MMD-12FD-R22M-V1Q'      | 'CHIP'         | ''          | ''   | '20151223'  
 '0.22UH/53A'                   | 'SMLF'     | 'EMPTY'  | 'CV+22^0MZ26'(!)           = ''              | ''                 | 'CV+22^0MZ26'              |'L_MMD12FD'| 'NA'                           | 'IO'       | 'IND SMD 0.22UH 20% 53A(MMD-12FD-R22M-V1Q'      | 'CHIP'         | ''          | ''   | '20151223'  
 '80NH/52A'                     | 'SMLF'     | 'IND'    | 'CVA80^0EZ00'(!)           = ''              | ''                 | 'CVA80^0EZ00'              |'L_SL2026-R08LHF'| '80NH/52A'                     | 'DISCRETE' | 'IND SMD 80NH 15% 52A(SL2026-R08LHF)'           | 'CHIP'         | ''          | ''   | '20151228'  
 '80NH/52A'                     | 'SMLF'     | 'EMPTY'  | 'CVA80^0EZ00'(!)           = ''              | ''                 | 'CVA80^0EZ00'              |'L_SL2026-R08LHF'| 'NA'                           | 'IO'       | 'IND SMD 80NH 15% 52A(SL2026-R08LHF)'           | 'CHIP'         | ''          | ''   | '20151228'  
 '1.5UH/27A'                    | 'SMLF'     | 'IND'    | 'CV-15S0MZ01'(!)           = ''              | ''                 | 'CV-15S0MZ01'              |'L_MMD12FD'| '1.5UH/27A'                    | 'DISCRETE' | 'IND SMD 1.5UH 20% 27A(MMD-12FD-1R5M-B1Q)'      | 'CHIP'         | ''          | ''   | '20151231'  
 '1.5UH/27A'                    | 'SMLF'     | 'EMPTY'  | 'CV-15S0MZ01'(!)           = ''              | ''                 | 'CV-15S0MZ01'              |'L_MMD12FD'| 'NA'                           | 'IO'       | 'IND SMD 1.5UH 20% 27A(MMD-12FD-1R5M-B1Q)'      | 'CHIP'         | ''          | ''   | '20151231'  
 '100NH/16A'                    | 'SMLF'     | 'IND'    | 'CV+10G0MZ05'(!)           = ''              | ''                 | 'CV+10G0MZ05'              |'L_HCBS404045_4X4'| '100NH/16A'                    | 'DISCRETE' | 'IND SMD 100NH 20% 16A(HCBS404045-101)'         | 'CHIP'         | ''          | ''   | '20160104'  
 '100NH/16A'                    | 'SMLF'     | 'EMPTY'  | 'CV+10G0MZ05'(!)           = ''              | ''                 | 'CV+10G0MZ05'              |'L_HCBS404045_4X4'| 'NA'                           | 'IO'       | 'IND SMD 100NH 20% 16A(HCBS404045-101)'         | 'CHIP'         | ''          | ''   | '20160104'  
 '80NH/50A'                     | 'SMLF'     | 'IND'    | 'CVA80^0MZ01'(!)           = ''              | ''                 | 'CVA80^0MZ01'              |'L_HCBS5265_5-2X5-2'| '80NH/50A'                     | 'DISCRETE' | 'IND SMD 80NH 20% 50A(HCBS5265-800)'            | 'CHIP'         | ''          | ''   | '20160104'  
 '80NH/50A'                     | 'SMLF'     | 'EMPTY'  | 'CVA80^0MZ01'(!)           = ''              | ''                 | 'CVA80^0MZ01'              |'L_HCBS5265_5-2X5-2'| 'NA'                           | 'IO'       | 'IND SMD 80NH 20% 50A(HCBS5265-800)'            | 'CHIP'         | ''          | ''   | '20160104'  
 'BLM18SN220TN1D/8000MA'        | 'SMLF'     | 'IND'    | 'CX220TN1001'(!)           = 'End of Design' | 'Comp-Approve'     | 'CX220TN1001'              |'L0603'| 'BLM18SN220TN1D/8000MA'        | 'DISCRETE' | 'EMI FILTER BLM18SN220TN1D(22,8000MA)'          | 'CHIP'         | ''          | ''   | '20160104'  
 'BLM18SN220TN1D/8000MA'        | 'SMLF'     | 'EMPTY'  | 'CX220TN1001'(!)           = 'End of Design' | 'Comp-Approve'     | 'CX220TN1001'              |'L0603'| 'NA'                           | 'IO'       | 'EMI FILTER BLM18SN220TN1D(22,8000MA)'          | 'CHIP'         | ''          | ''   | '20160104'  
 '0.88UH/20A'                   | 'SMLF'     | 'IND'    | 'CV+88K0MZ01'(!)           = ''              | ''                 | 'CV+88K0MZ01'              |'L_PCMC104T'| '0.88UH/20A'                   | 'DISCRETE' | 'IND SMD 0.88UH +-20% 20A(PCMC104T-R88MN)'      | 'CHIP'         | ''          | ''   | '20160112'  
 '0.88UH/20A'                   | 'SMLF'     | 'EMPTY'  | 'CV+88K0MZ01'(!)           = ''              | ''                 | 'CV+88K0MZ01'              |'L_PCMC104T'| 'NA'                           | 'IO'       | 'IND SMD 0.88UH +-20% 20A(PCMC104T-R88MN)'      | 'CHIP'         | ''          | ''   | '20160112'  
 'FBMJ2125HS250NT/6A'           | 'SMLF'     | 'IND'    | 'CX0250NT006'(!)           = 'End of Design' | 'Comp-Approve'     | 'CX0250NT006'              |'L0805'| 'FBMJ2125HS250NT/6A'           | 'DISCRETE' | 'EMI FILTER CHIP FBMJ2125HS250NT(25,6A)'        | 'CHIP'         | ''          | ''   | '20160120'  
 'FBMJ2125HS250NT/6A'           | 'SMLF'     | 'EMPTY'  | 'CX0250NT006'(!)           = 'End of Design' | 'Comp-Approve'     | 'CX0250NT006'              |'L0805'| 'NA'                           | 'IO'       | 'EMI FILTER CHIP FBMJ2125HS250NT(25,6A)'        | 'CHIP'         | ''          | ''   | '20160120'  
 '2.2UH/5.6A'                   | 'SMLF'     | 'IND'    | 'CV-2256MZ00'(!)           = ''              | ''                 | 'CV-2256MZ00'              |'L_XAL4020-222MEC'| '2.2UH/5.6A'                   | 'DISCRETE' | 'IND SMD 2.2U 20% 5.6A(XAL4020-222MEC)AEC'      | 'CHIP'         | ''          | ''   | '20160203'  
 '2.2UH/5.6A'                   | 'SMLF'     | 'EMPTY'  | 'CV-2256MZ00'(!)           = ''              | ''                 | 'CV-2256MZ00'              |'L_XAL4020-222MEC'| 'NA'                           | 'IO'       | 'IND SMD 2.2U 20% 5.6A(XAL4020-222MEC)AEC'      | 'CHIP'         | ''          | ''   | '20160203'  
 '120NH/94A'                    | 'SMLF'     | 'IND'    | 'CV+12^0KZ06'(!)           = 'End of Design' | 'Comp-Approve'     | 'CV+12^0KZ06'              |'L_SLA3735B'| '120NH/94A'                    | 'DISCRETE' | 'IND SMD 120NH 10% 94A(SLA3735B-120K)'          | 'CHIP'         | ''          | ''   | '20160203'  
 '120NH/94A'                    | 'SMLF'     | 'EMPTY'  | 'CV+12^0KZ06'(!)           = 'End of Design' | 'Comp-Approve'     | 'CV+12^0KZ06'              |'L_SLA3735B'| 'NA'                           | 'IO'       | 'IND SMD 120NH 10% 94A(SLA3735B-120K)'          | 'CHIP'         | ''          | ''   | '20160203'  
 '150NH/75A'                    | 'SMLF'     | 'IND'    | 'CV+15^0KZ09'(!)           = 'End of Design' | 'Comp-Approve'     | 'CV+15^0KZ09'              |'L_SLA3735B'| '150NH/75A'                    | 'DISCRETE' | 'IND SMD 150NH 10% 75A(SLA3735B-150K)'          | 'CHIP'         | ''          | ''   | '20160203'  
 '150NH/75A'                    | 'SMLF'     | 'EMPTY'  | 'CV+15^0KZ09'(!)           = 'End of Design' | 'Comp-Approve'     | 'CV+15^0KZ09'              |'L_SLA3735B'| 'NA'                           | 'IO'       | 'IND SMD 150NH 10% 75A(SLA3735B-150K)'          | 'CHIP'         | ''          | ''   | '20160203'  
 '300NH/33A'                    | 'SMLF'     | 'IND'    | 'CV+30Y0KZ01'(!)           = 'End of Design' | 'Comp-Approve'     | 'CV+30Y0KZ01'              |'L_SLA3735B'| '300NH/33A'                    | 'DISCRETE' | 'IND SMD 300NH 10% 33A(SLA3735B-300K)'          | 'CHIP'         | ''          | ''   | '20160203'  
 '300NH/33A'                    | 'SMLF'     | 'EMPTY'  | 'CV+30Y0KZ01'(!)           = 'End of Design' | 'Comp-Approve'     | 'CV+30Y0KZ01'              |'L_SLA3735B'| 'NA'                           | 'IO'       | 'IND SMD 300NH 10% 33A(SLA3735B-300K)'          | 'CHIP'         | ''          | ''   | '20160203'  
 '2.2UH/45A'                    | 'SMLF'     | 'IND'    | 'CV-22^0MZ04'(!)           = ''              | ''                 | 'CV-22^0MZ04'              |'L_MSE-12FDE_13-2X12-9'| '2.2UH/45A'                    | 'DISCRETE' | 'IND SMD 2.2UH 20% 45A(MSE-12FDE2R2M-M1Q)'      | 'CHIP'         | ''          | ''   | '20160204'  
 '2.2UH/45A'                    | 'SMLF'     | 'EMPTY'  | 'CV-22^0MZ04'(!)           = ''              | ''                 | 'CV-22^0MZ04'              |'L_MSE-12FDE_13-2X12-9'| 'NA'                           | 'IO'       | 'IND SMD 2.2UH 20% 45A(MSE-12FDE2R2M-M1Q)'      | 'CHIP'         | ''          | ''   | '20160204'  
 '600NH/18A'                    | 'SMLF'     | 'IND'    | 'CV+60I0KZ01'(!)           = 'End of Design' | 'Comp-Approve'     | 'CV+60I0KZ01'              |'L_HCUVD6595D-601KLY_6-5X6-5'| '600NH/18A'                    | 'DISCRETE' | 'IND SMD 600NH 10% 18A(HCUVD6595D-601KLY)'      | 'CHIP'         | ''          | ''   | '20160204'  
 '600NH/18A'                    | 'SMLF'     | 'EMPTY'  | 'CV+60I0KZ01'(!)           = 'End of Design' | 'Comp-Approve'     | 'CV+60I0KZ01'              |'L_HCUVD6595D-601KLY_6-5X6-5'| 'NA'                           | 'IO'       | 'IND SMD 600NH 10% 18A(HCUVD6595D-601KLY)'      | 'CHIP'         | ''          | ''   | '20160204'  
 '1UH/11A'                      | 'SMLF'     | 'IND'    | 'CV-10B0KZ01'(!)           = 'End of Design' | 'Comp-Approve'     | 'CV-10B0KZ01'              |'L_HCUVD6595D-601KLY_6-5X6-5'| '1UH/11A'                      | 'DISCRETE' | 'IND SMD 1UH 10% 11A(HCUVD6595D-102KLY)'        | 'CHIP'         | ''          | ''   | '20160204'  
 '1UH/11A'                      | 'SMLF'     | 'EMPTY'  | 'CV-10B0KZ01'(!)           = 'End of Design' | 'Comp-Approve'     | 'CV-10B0KZ01'              |'L_HCUVD6595D-601KLY_6-5X6-5'| 'NA'                           | 'IO'       | 'IND SMD 1UH 10% 11A(HCUVD6595D-102KLY)'        | 'CHIP'         | ''          | ''   | '20160204'  
 '0.1UH/16A'                    | 'SMLF'     | 'IND'    | 'CV+10G0MZ06'(!)           = 'End of Design' | 'Comp-Approve'     | 'CV+10G0MZ06'              |'L_L30909-64_4X4'| '0.1UH/16A'                    | 'DISCRETE' | 'IND SMD 0.1UH 20% 16A(L30909-64)'              | 'CHIP'         | ''          | ''   | '20160215'  
 '0.1UH/16A'                    | 'SMLF'     | 'EMPTY'  | 'CV+10G0MZ06'(!)           = 'End of Design' | 'Comp-Approve'     | 'CV+10G0MZ06'              |'L_L30909-64_4X4'| 'NA'                           | 'IO'       | 'IND SMD 0.1UH 20% 16A(L30909-64)'              | 'CHIP'         | ''          | ''   | '20160215'  
 '0.08UH/50A'                   | 'SMLF'     | 'IND'    | 'CVA80^0EZ01'(!)           = 'End of Design' | 'Comp-Approve'     | 'CVA80^0EZ01'              |'L_L30909-63_5-2X5-2'| '0.08UH/50A'                   | 'DISCRETE' | 'IND SMD 0.08UH 15% 50A(L30909-63)'             | 'CHIP'         | ''          | ''   | '20160215'  
 '0.08UH/50A'                   | 'SMLF'     | 'EMPTY'  | 'CVA80^0EZ01'(!)           = 'End of Design' | 'Comp-Approve'     | 'CVA80^0EZ01'              |'L_L30909-63_5-2X5-2'| 'NA'                           | 'IO'       | 'IND SMD 0.08UH 15% 50A(L30909-63)'             | 'CHIP'         | ''          | ''   | '20160215'  
 '2.2UH/50A'                    | 'SMLF'     | 'IND'    | 'CV-22^0MZ05'(!)           = ''              | ''                 | 'CV-22^0MZ05'              |'L_MSE-12FDE_13-2X12-9_H315'| '2.2UH/50A'                    | 'DISCRETE' | 'IND SMD 2.2UH 20% 50A(MSE-12HZE2R2M-M1Q)'      | 'CHIP'         | ''          | ''   | '20160215'  
 '2.2UH/50A'                    | 'SMLF'     | 'EMPTY'  | 'CV-22^0MZ05'(!)           = ''              | ''                 | 'CV-22^0MZ05'              |'L_MSE-12FDE_13-2X12-9_H315'| 'NA'                           | 'IO'       | 'IND SMD 2.2UH 20% 50A(MSE-12HZE2R2M-M1Q)'      | 'CHIP'         | ''          | ''   | '20160215'  
 'BLM41PG181SN1L/3.5A'          | 'SMLF'     | 'IND'    | 'CX1PG181000'(!)           = ''              | ''                 | 'CX1PG181000'              |'L1806'| 'BLM41PG181SN1L/3.5A'          | 'DISCRETE' | 'EMI FILTER BLM41PG181SN1L(180,3.5A)'           | 'CHIP'         | ''          | ''   | '20160216'  
 'BLM41PG181SN1L/3.5A'          | 'SMLF'     | 'EMPTY'  | 'CX1PG181000'(!)           = ''              | ''                 | 'CX1PG181000'              |'L1806'| 'NA'                           | 'IO'       | 'EMI FILTER BLM41PG181SN1L(180,3.5A)'           | 'CHIP'         | ''          | ''   | '20160216'  
 '1UH/17A'                      | 'SMLF'     | 'IND'    | 'CV-10H0KZ01'(!)           = ''              | ''                 | 'CV-10H0KZ01'              |'L_HCUVD8095D-102KQL_8X8'| '1UH/17A'                      | 'DISCRETE' | 'IND SMD 1UH 10% 17A(HCUVD8095D-102KQL)'        | 'CHIP'         | ''          | ''   | '20160216'  
 '1UH/17A'                      | 'SMLF'     | 'EMPTY'  | 'CV-10H0KZ01'(!)           = ''              | ''                 | 'CV-10H0KZ01'              |'L_HCUVD8095D-102KQL_8X8'| 'NA'                           | 'IO'       | 'IND SMD 1UH 10% 17A(HCUVD8095D-102KQL)'        | 'CHIP'         | ''          | ''   | '20160216'  
 '4.7UH/650MA'                  | 'SMLF'     | 'IND'    | 'CV-4707MZ01'(!)           = 'End of Design' | 'Comp-Approve'     | 'CV-4707MZ01'              |'L1210XC'| '4.7UH'                        | 'DISCRETE' | 'IND SMD 4.7UH 20% 650MA(LQH32CN4R7M33L)'       | 'CHIP'         | ''          | ''   | '20160218'  
 '4.7UH/650MA'                  | 'SMLF'     | 'EMPTY'  | 'CV-4707MZ01'(!)           = 'End of Design' | 'Comp-Approve'     | 'CV-4707MZ01'              |'L1210XC'| 'NA'                           | 'IO'       | 'IND SMD 4.7UH 20% 650MA(LQH32CN4R7M33L)'       | 'CHIP'         | ''          | ''   | '20160218'  
 '0.24UH/4.7A'                  | 'SMLF'     | 'IND'    | 'CV+2447MZ00'(!)           = ''              | ''                 | 'CV+2447MZ00'              |'L_HTTN20161T-R24MDR'| '0.24UH/4.7A'                  | 'DISCRETE' | 'IND SMD 0.24U 20% 4.7A(HTTN20161T-R24MDR'      | 'CHIP'         | ''          | ''   | '20160222'  
 '0.24UH/4.7A'                  | 'SMLF'     | 'EMPTY'  | 'CV+2447MZ00'(!)           = ''              | ''                 | 'CV+2447MZ00'              |'L_HTTN20161T-R24MDR'| 'NA'                           | 'IO'       | 'IND SMD 0.24U 20% 4.7A(HTTN20161T-R24MDR'      | 'CHIP'         | ''          | ''   | '20160222'  
 'PBY160808T-601Y-N(600/1A)'    | 'SMLF'     | 'IND'    | 'CX08T601000'(!)           = ''              | ''                 | 'CX08T601000'              |'L0603'| 'PBY160808T-601Y-N(600/1A)'    | 'DISCRETE' | 'EMI FILTER PBY160808T-601Y-N(600.1A)'          | 'CHIP'         | ''          | ''   | '20160222'  
 'PBY160808T-601Y-N(600/1A)'    | 'SMLF'     | 'EMPTY'  | 'CX08T601000'(!)           = ''              | ''                 | 'CX08T601000'              |'L0603'| 'NA'                           | 'IO'       | 'EMI FILTER PBY160808T-601Y-N(600.1A)'          | 'CHIP'         | ''          | ''   | '20160222'  
 'GMLB-201209-0330P-N8(330/3A)' | 'SMLF'     | 'IND'    | 'CX090330000'(!)           = ''              | ''                 | 'CX090330000'              |'L0805'| 'GMLB-201209-0330P-N8(330/3A)' | 'DISCRETE' | 'EMI FILTER GMLB-201209-0330P-N8(330,3A)'       | 'CHIP'         | ''          | ''   | '20160222'  
 'GMLB-201209-0330P-N8(330/3A)' | 'SMLF'     | 'EMPTY'  | 'CX090330000'(!)           = ''              | ''                 | 'CX090330000'              |'L0805'| 'NA'                           | 'IO'       | 'EMI FILTER GMLB-201209-0330P-N8(330,3A)'       | 'CHIP'         | ''          | ''   | '20160222'  
 'GMLB-201209-0600P-N8/2A'      | 'SMLF'     | 'IND'    | 'CX090600001'(!)           = ''              | 'End of Life'      | 'CX090600001'              |'L0805_EOL'| 'GMLB-201209-0600P-N8/2A'      | 'DISCRETE' | 'EMI FILTER GMLB-201209-0600P-N8(600,2A)'       | 'CHIP'         | ''          | ''   | '20160223'  
 'GMLB-201209-0600P-N8/2A'      | 'SMLF'     | 'EMPTY'  | 'CX090600001'(!)           = ''              | 'End of Life'      | 'CX090600001'              |'L0805_EOL'| 'NA'                           | 'IO'       | 'EMI FILTER GMLB-201209-0600P-N8(600,2A)'       | 'CHIP'         | ''          | ''   | '20160223'  
 'UPB201209T-300Y-N/5A'         | 'SMLF'     | 'IND'    | 'CX09T300012'(!)           = ''              | ''                 | 'CX09T300012'              |'L0805'| 'UPB201209T-300Y-N/5A'         | 'DISCRETE' | 'EMI FILTER UPB201209T-300Y-N(30,5A)'           | 'CHIP'         | ''          | ''   | '20160223'  
 'UPB201209T-300Y-N/5A'         | 'SMLF'     | 'EMPTY'  | 'CX09T300012'(!)           = ''              | ''                 | 'CX09T300012'              |'L0805'| 'NA'                           | 'IO'       | 'EMI FILTER UPB201209T-300Y-N(30,5A)'           | 'CHIP'         | ''          | ''   | '20160223'  
 'BLM18KG300TN1D/5A'            | 'SMLF'     | 'IND'    | 'CX8KG300001'(!)           = ''              | ''                 | 'CX8KG300001'              |'L0603'| 'BLM18KG300TN1D/5A'            | 'DISCRETE' | 'EMI FILTER BLM18KG300TN1D(30,5A)'              | 'CHIP'         | ''          | ''   | '20160223'  
 'BLM18KG300TN1D/5A'            | 'SMLF'     | 'EMPTY'  | 'CX8KG300001'(!)           = ''              | ''                 | 'CX8KG300001'              |'L0603'| 'NA'                           | 'IO'       | 'EMI FILTER BLM18KG300TN1D(30,5A)'              | 'CHIP'         | ''          | ''   | '20160223'  
 '0.24UH/4.4A'                  | 'SMLF'     | 'IND'    | 'CV+2444TZ00'(!)           = ''              | ''                 | 'CV+2444TZ00'              |'L_MLV-TP10NR24N-XP_2X1-6'| '0.24UH/4.4A'                  | 'DISCRETE' | 'IND SMD 0.24UH30% 4.4A MLV-TP10NR24N-XPQ'      | 'CHIP'         | ''          | ''   | '20160302'  
 '0.24UH/4.4A'                  | 'SMLF'     | 'EMPTY'  | 'CV+2444TZ00'(!)           = ''              | ''                 | 'CV+2444TZ00'              |'L_MLV-TP10NR24N-XP_2X1-6'| 'NA'                           | 'IO'       | 'IND SMD 0.24UH30% 4.4A MLV-TP10NR24N-XPQ'      | 'CHIP'         | ''          | ''   | '20160302'  
 '210NH/47A'                    | 'SMLF'     | 'IND'    | 'CV+21^0KZ00'(!)           = ''              | ''                 | 'CV+21^0KZ00'              |'L_HCUVE966490D-121'| '210NH/47A'                    | 'DISCRETE' | 'IND SMD 210NH 10% 47A(HCUVE966490D-211)'       | 'CHIP'         | ''          | ''   | '20160302'  
 '210NH/47A'                    | 'SMLF'     | 'EMPTY'  | 'CV+21^0KZ00'(!)           = ''              | ''                 | 'CV+21^0KZ00'              |'L_HCUVE966490D-121'| 'NA'                           | 'IO'       | 'IND SMD 210NH 10% 47A(HCUVE966490D-211)'       | 'CHIP'         | ''          | ''   | '20160302'  
 '2.2UH/2.5A'                   | 'SMLF'     | 'IND'    | 'CV-2225MZ02'(!)           = ''              | ''                 | 'CV-2225MZ02'              |'L_LVS404018_4X4'| '2.2UH/2.5A'                   | 'DISCRETE' | 'IND SMD 2.2UH 20% 2.5A(LVS404018-2R2M-N)'      | 'CHIP'         | ''          | ''   | '20160303'  
 '2.2UH/2.5A'                   | 'SMLF'     | 'EMPTY'  | 'CV-2225MZ02'(!)           = ''              | ''                 | 'CV-2225MZ02'              |'L_LVS404018_4X4'| 'NA'                           | 'IO'       | 'IND SMD 2.2UH 20% 2.5A(LVS404018-2R2M-N)'      | 'CHIP'         | ''          | ''   | '20160303'  
 '250NH/38A'                    | 'SMLF'     | 'IND'    | 'CV+25^0KZ05'(!)           = ''              | ''                 | 'CV+25^0KZ05'              |'L_HCUVD6270_6-2X5-5XA'| '250NH/38A'                    | 'DISCRETE' | 'IND SMD 250NH 10% 38A(HCUVD6270-251KLY)'       | 'CHIP'         | ''          | ''   | '20160329'  
 '250NH/38A'                    | 'SMLF'     | 'EMPTY'  | 'CV+25^0KZ05'(!)           = ''              | ''                 | 'CV+25^0KZ05'              |'L_HCUVD6270_6-2X5-5XA'| 'NA'                           | 'IO'       | 'IND SMD 250NH 10% 38A(HCUVD6270-251KLY)'       | 'CHIP'         | ''          | ''   | '20160329'  
 '4.7UH/650MA'                  | 'SMLF'     | 'IND'    | 'CV-4707MZ19'(!)           = ''              | ''                 | 'CV-4707MZ19'              |'L1210XC'| '4.7UH/650MA'                  | 'DISCRETE' | 'INDSMD 4.7U 20% 650MA(LQH32CH4R7M33L)AEC'      | 'CHIP'         | ''          | ''   | '20160330'  
 '4.7UH/650MA'                  | 'SMLF'     | 'EMPTY'  | 'CV-4707MZ19'(!)           = ''              | ''                 | 'CV-4707MZ19'              |'L1210XC'| 'NA'                           | 'IO'       | 'INDSMD 4.7U 20% 650MA(LQH32CH4R7M33L)AEC'      | 'CHIP'         | ''          | ''   | '20160330'  
 'BLM18PG121SZ1D/2A'            | 'SMLF'     | 'IND'    | 'CX000121002'(!)           = ''              | ''                 | 'CX000121002'              |'L0603'| 'BLM18PG121SZ1D/2A'            | 'DISCRETE' | 'EMI FILTER BLM18PG121SZ1D(120,2A)AEC'          | 'CHIP'         | ''          | ''   | '20160330'  
 'BLM18PG121SZ1D/2A'            | 'SMLF'     | 'EMPTY'  | 'CX000121002'(!)           = ''              | ''                 | 'CX000121002'              |'L0603'| 'NA'                           | 'IO'       | 'EMI FILTER BLM18PG121SZ1D(120,2A)AEC'          | 'CHIP'         | ''          | ''   | '20160330'  
 'BLM21PG331SZ1D/1.5A'          | 'SMLF'     | 'IND'    | 'CX000331004'(!)           = ''              | ''                 | 'CX000331004'              |'L0805'| 'BLM21PG331SZ1D/1.5A'          | 'DISCRETE' | 'EMI FILTER BLM21PG331SZ1D(330,1.5A)AEC'        | 'CHIP'         | ''          | ''   | '20160330'  
 'BLM21PG331SZ1D/1.5A'          | 'SMLF'     | 'EMPTY'  | 'CX000331004'(!)           = ''              | ''                 | 'CX000331004'              |'L0805'| 'NA'                           | 'IO'       | 'EMI FILTER BLM21PG331SZ1D(330,1.5A)AEC'        | 'CHIP'         | ''          | ''   | '20160330'  
 'BLM21AG601SZ1D/0.7A'          | 'SMLF'     | 'IND'    | 'CX000601003'(!)           = ''              | ''                 | 'CX000601003'              |'L0805'| 'BLM21AG601SZ1D/0.7A'          | 'DISCRETE' | 'EMI FILTER BLM21AG601SZ1D(600,0.7A)AEC'        | 'CHIP'         | ''          | ''   | '20160330'  
 'BLM21AG601SZ1D/0.7A'          | 'SMLF'     | 'EMPTY'  | 'CX000601003'(!)           = ''              | ''                 | 'CX000601003'              |'L0805'| 'NA'                           | 'IO'       | 'EMI FILTER BLM21AG601SZ1D(600,0.7A)AEC'        | 'CHIP'         | ''          | ''   | '20160330'  
 'SMB-853025/10A'               | 'SMLF'     | 'IND'    | 'CX853025000'(!)           = ''              | ''                 | 'CX853025000'              |'L_SMB-853025'| 'SMB-853025/10A'               | 'DISCRETE' | 'EMI FILTER SMB-853025 (90,10A)'                | 'CHIP'         | ''          | ''   | '20160408'  
 'SMB-853025/10A'               | 'SMLF'     | 'EMPTY'  | 'CX853025000'(!)           = ''              | ''                 | 'CX853025000'              |'L_SMB-853025'| 'NA'                           | 'IO'       | 'EMI FILTER SMB-853025 (90,10A)'                | 'CHIP'         | ''          | ''   | '20160408'  
 '1UH/17A'                      | 'SMLF'     | 'IND'    | 'CV-10H0KZ02'(!)           = 'End of Design' | 'Comp-Approve'     | 'CV-10H0KZ02'              |'L_HCUVD8095D-102KBQL_8X8'| '1UH/17A'                      | 'DISCRETE' | 'IND SMD 1UH 10% 17A(HCUVD8095D-102KBQL)'       | 'CHIP'         | ''          | ''   | '20160408'  
 '1UH/17A'                      | 'SMLF'     | 'EMPTY'  | 'CV-10H0KZ02'(!)           = 'End of Design' | 'Comp-Approve'     | 'CV-10H0KZ02'              |'L_HCUVD8095D-102KBQL_8X8'| 'NA'                           | 'IO'       | 'IND SMD 1UH 10% 17A(HCUVD8095D-102KBQL)'       | 'CHIP'         | ''          | ''   | '20160408'  
 '940NH/19A'                    | 'SMLF'     | 'IND'    | 'CV+94J0KZ01'(!)           = ''              | ''                 | 'CV+94J0KZ01'              |'L_HCUVD8083_8X8'| '940NH/19A'                    | 'DISCRETE' | 'IND SMD 940NH 10% 19A(HCUVD8083-941HK)'        | 'CHIP'         | ''          | ''   | '20160414'  
 '940NH/19A'                    | 'SMLF'     | 'EMPTY'  | 'CV+94J0KZ01'(!)           = ''              | ''                 | 'CV+94J0KZ01'              |'L_HCUVD8083_8X8'| 'NA'                           | 'IO'       | 'IND SMD 940NH 10% 19A(HCUVD8083-941HK)'        | 'CHIP'         | ''          | ''   | '20160414'  
 '560NH/32A'                    | 'SMLF'     | 'IND'    | 'CV+56X0KZ01'(!)           = ''              | ''                 | 'CV+56X0KZ01'              |'L_HCUVD8083_8X8'| '560NH/32A'                    | 'DISCRETE' | 'IND SMD 560NH 10% 32A(HCUVD8083-561HK)'        | 'CHIP'         | ''          | ''   | '20160414'  
 '560NH/32A'                    | 'SMLF'     | 'EMPTY'  | 'CV+56X0KZ01'(!)           = ''              | ''                 | 'CV+56X0KZ01'              |'L_HCUVD8083_8X8'| 'NA'                           | 'IO'       | 'IND SMD 560NH 10% 32A(HCUVD8083-561HK)'        | 'CHIP'         | ''          | ''   | '20160414'  
 'FCM1608KF-470T05/0.5A'        | 'SMLF'     | 'IND'    | 'CX470T05000'(!)           = ''              | ''                 | 'CX470T05000'              |'L0603'| 'FCM1608KF-470T05/0.5A'        | 'DISCRETE' | 'EMI FILTER FCM1608KF-470T05(47,0.5A)'          | 'CHIP'         | ''          | ''   | '20160415'  
 'FCM1608KF-470T05/0.5A'        | 'SMLF'     | 'EMPTY'  | 'CX470T05000'(!)           = ''              | ''                 | 'CX470T05000'              |'L0603'| 'NA'                           | 'IO'       | 'EMI FILTER FCM1608KF-470T05(47,0.5A)'          | 'CHIP'         | ''          | ''   | '20160415'  
 'BLM15PX121SN1D/2A'            | 'SMLF'     | 'IND'    | 'CX5PX121001'(!)           = ''              | ''                 | 'CX5PX121001'              |'L0402'| 'BLM15PX121SN1D/2A'            | 'DISCRETE' | 'EMI FILTER BLM15PX121SN1D(120,2A)'             | 'CHIP'         | ''          | ''   | '20160425'  
 'BLM15PX121SN1D/2A'            | 'SMLF'     | 'EMPTY'  | 'CX5PX121001'(!)           = ''              | ''                 | 'CX5PX121001'              |'L0402'| 'NA'                           | 'IO'       | 'EMI FILTER BLM15PX121SN1D(120,2A)'             | 'CHIP'         | ''          | ''   | '20160425'  
 '1.5UH/4A'                     | 'SMLF'     | 'IND'    | 'DC-1540M000'(!)           = ''              | ''                 | 'DC-1540M000'              |'L_PCMB042T'| '1.5UH/4A'                     | 'DISCRETE' | 'CHOKE 1.5UH +-20% 4A(PCMB042T-1R5MS)'          | 'CHIP'         | ''          | ''   | '20160425'  
 '1.5UH/4A'                     | 'SMLF'     | 'EMPTY'  | 'DC-1540M000'(!)           = ''              | ''                 | 'DC-1540M000'              |'L_PCMB042T'| 'NA'                           | 'IO'       | 'CHOKE 1.5UH +-20% 4A(PCMB042T-1R5MS)'          | 'CHIP'         | ''          | ''   | '20160425'  
 'BLM31PG500SN1L/3A'            | 'SMLF'     | 'IND'    | 'CX1PG500007'(!)           = ''              | ''                 | 'CX1PG500007'              |'L1206'| 'BLM31PG500SN1L/3A'            | 'DISCRETE' | 'EMI FILTER CHIP BLM31PG500SN1L(50.3A)EP'       | 'CHIP'         | ''          | ''   | '20160427'  
 'BLM31PG500SN1L/3A'            | 'SMLF'     | 'EMPTY'  | 'CX1PG500007'(!)           = ''              | ''                 | 'CX1PG500007'              |'L1206'| 'NA'                           | 'IO'       | 'EMI FILTER CHIP BLM31PG500SN1L(50.3A)EP'       | 'CHIP'         | ''          | ''   | '20160427'  
 '400NH/17.5A'                  | 'SMLF'     | 'IND'    | 'CV+40H5KZ00'(!)           = ''              | ''                 | 'CV+40H5KZ00'              |'L_HCUVE966490D-121'| '400NH/17.5A'                  | 'DISCRETE' | 'IND SMD 400NH 10% 17.5A(HCUVE966490D-401'      | 'CHIP'         | ''          | ''   | '20160512'  
 '400NH/17.5A'                  | 'SMLF'     | 'EMPTY'  | 'CV+40H5KZ00'(!)           = ''              | ''                 | 'CV+40H5KZ00'              |'L_HCUVE966490D-121'| 'NA'                           | 'IO'       | 'IND SMD 400NH 10% 17.5A(HCUVE966490D-401'      | 'CHIP'         | ''          | ''   | '20160512'  
 '3.3UH/15A'                    | 'SMLF'     | 'IND'    | 'CV-33F0MZ00'(!)           = ''              | ''                 | 'CV-33F0MZ00'              |'L_MAC-12EZ_13-2X12-9'| '3.3UH/15A'                    | 'DISCRETE' | 'IND SMD 3.3UH 20% 15A(MAC-12EZ-3R3M)AEC'       | 'CHIP'         | ''          | ''   | '20160516'  
 '3.3UH/15A'                    | 'SMLF'     | 'EMPTY'  | 'CV-33F0MZ00'(!)           = ''              | ''                 | 'CV-33F0MZ00'              |'L_MAC-12EZ_13-2X12-9'| 'NA'                           | 'IO'       | 'IND SMD 3.3UH 20% 15A(MAC-12EZ-3R3M)AEC'       | 'CHIP'         | ''          | ''   | '20160516'  
 '0.82UH/31A'                   | 'SMLF'     | 'IND'    | 'CV+82W0MZ02'(!)           = ''              | ''                 | 'CV+82W0MZ02'              |'L_MAC-12EZ_13-2X12-9'| '0.82UH/31A'                   | 'DISCRETE' | 'IND SMD 0.82UH 20% 31A(MAC-12EZ-R82M)AEC'      | 'CHIP'         | ''          | ''   | '20160516'  
 '0.82UH/31A'                   | 'SMLF'     | 'EMPTY'  | 'CV+82W0MZ02'(!)           = ''              | ''                 | 'CV+82W0MZ02'              |'L_MAC-12EZ_13-2X12-9'| 'NA'                           | 'IO'       | 'IND SMD 0.82UH 20% 31A(MAC-12EZ-R82M)AEC'      | 'CHIP'         | ''          | ''   | '20160516'  
 '3.3UH/10A'                    | 'SMLF'     | 'IND'    | 'CV-33A0MZ03'(!)           = ''              | ''                 | 'CV-33A0MZ03'              |'L_MAC-10DZ_11-5X10'| '3.3UH/10A'                    | 'DISCRETE' | 'IND SMD 3.3UH 20% 10A(MAC-10DZ-3R3M)AEC'       | 'CHIP'         | ''          | ''   | '20160516'  
 '3.3UH/10A'                    | 'SMLF'     | 'EMPTY'  | 'CV-33A0MZ03'(!)           = ''              | ''                 | 'CV-33A0MZ03'              |'L_MAC-10DZ_11-5X10'| 'NA'                           | 'IO'       | 'IND SMD 3.3UH 20% 10A(MAC-10DZ-3R3M)AEC'       | 'CHIP'         | ''          | ''   | '20160516'  
 'MLB-201209-0330P-N2/1.5A'     | 'SMLF'     | 'IND'    | 'CX00330P000'(!)           = 'End of Design' | 'Comp-Approve'     | 'CX00330P000'              |'L0805'| 'MLB-201209-0330P-N2/1.5A'     | 'DISCRETE' | 'FILTER MLB-201209-0330P-N2 (330,1.5A)'         | 'CHIP'         | ''          | ''   | '20160513'  
 'MLB-201209-0330P-N2/1.5A'     | 'SMLF'     | 'EMPTY'  | 'CX00330P000'(!)           = 'End of Design' | 'Comp-Approve'     | 'CX00330P000'              |'L0805'| 'NA'                           | 'IO'       | 'FILTER MLB-201209-0330P-N2 (330,1.5A)'         | 'CHIP'         | ''          | ''   | '20160513'  
 '90NH/150A'                    | 'SMLF'     | 'IND'    | 'CVA90^0KZ00'(!)           = ''              | 'End of Life'      | 'CVA90^0KZ00'              |'L_HCUVE966490D-121_EOL'| '90NH/150A'                    | 'DISCRETE' | 'IND SMD 90NH 10% 150A(HCUVE966490D-900)'       | 'CHIP'         | ''          | ''   | '20160520'  
 '90NH/150A'                    | 'SMLF'     | 'EMPTY'  | 'CVA90^0KZ00'(!)           = ''              | 'End of Life'      | 'CVA90^0KZ00'              |'L_HCUVE966490D-121_EOL'| 'NA'                           | 'IO'       | 'IND SMD 90NH 10% 150A(HCUVE966490D-900)'       | 'CHIP'         | ''          | ''   | '20160520'  
 '2.2UH/970MA'                  | 'SMLF'     | 'IND'    | 'CV-2210TN00'(!)           = 'End of Design' | 'Comp-Approve'     | 'CV-2210TN00'              |'L1210XB'| '2.2UH/970MA'                  | 'DISCRETE' | 'IND CHIP 2.2UH 30% 970MA(LQH32PZ2R2NN0L)'      | 'CHIP'         | ''          | ''   | '20160526'  
 '2.2UH/970MA'                  | 'SMLF'     | 'EMPTY'  | 'CV-2210TN00'(!)           = 'End of Design' | 'Comp-Approve'     | 'CV-2210TN00'              |'L1210XB'| 'NA'                           | 'IO'       | 'IND CHIP 2.2UH 30% 970MA(LQH32PZ2R2NN0L)'      | 'CHIP'         | ''          | ''   | '20160526'  
 '0.47UH/38A'                   | 'SMLF'     | 'IND'    | 'CV+47^0MZ12'(!)           = ''              | ''                 | 'CV+47^0MZ12'              |'L_CMMS136E_13-45X12-6'| '0.47UH/38A'                   | 'DISCRETE' | 'IND SMD 0.47UH +-20% 38A(CMMS136E-R47MS)'      | 'CHIP'         | ''          | ''   | '20160613'  
 '0.47UH/38A'                   | 'SMLF'     | 'EMPTY'  | 'CV+47^0MZ12'(!)           = ''              | ''                 | 'CV+47^0MZ12'              |'L_CMMS136E_13-45X12-6'| 'NA'                           | 'IO'       | 'IND SMD 0.47UH +-20% 38A(CMMS136E-R47MS)'      | 'CHIP'         | ''          | ''   | '20160613'  
 '0.56UH/31A'                   | 'SMLF'     | 'IND'    | 'CV+56W0MZ01'(!)           = ''              | ''                 | 'CV+56W0MZ01'              |'L_VCMT104T-R56MN5'| '0.56UH/31A'                   | 'DISCRETE' | 'INDSMD 0.56U 20% 31A(VCMT104T-R56MN5)AEC'      | 'CHIP'         | ''          | ''   | '20160614'  
 '0.56UH/31A'                   | 'SMLF'     | 'EMPTY'  | 'CV+56W0MZ01'(!)           = ''              | ''                 | 'CV+56W0MZ01'              |'L_VCMT104T-R56MN5'| 'NA'                           | 'IO'       | 'INDSMD 0.56U 20% 31A(VCMT104T-R56MN5)AEC'      | 'CHIP'         | ''          | ''   | '20160614'  
 '2UH/16A'                      | 'SMLF'     | 'IND'    | 'CV-20G0MZ00'(!)           = ''              | ''                 | 'CV-20G0MZ00'              |'L_VCMT104T-R56MN5'| '2UH/16A'                      | 'DISCRETE' | 'IND SMD 2UH 20% 16A(VCMT104T-2R0MN5)AEC'       | 'CHIP'         | ''          | ''   | '20160614'  
 '2UH/16A'                      | 'SMLF'     | 'EMPTY'  | 'CV-20G0MZ00'(!)           = ''              | ''                 | 'CV-20G0MZ00'              |'L_VCMT104T-R56MN5'| 'NA'                           | 'IO'       | 'IND SMD 2UH 20% 16A(VCMT104T-2R0MN5)AEC'       | 'CHIP'         | ''          | ''   | '20160614'  
 '3.3UH/11A'                    | 'SMLF'     | 'IND'    | 'CV-33B0MZ02'(!)           = ''              | ''                 | 'CV-33B0MZ02'              |'L_VCMT104T-R56MN5'| '3.3UH/11A'                    | 'DISCRETE' | 'IND SMD 3.3U 20% 11A(VCMT104T-3R3MN5)AEC'      | 'CHIP'         | ''          | ''   | '20160614'  
 '3.3UH/11A'                    | 'SMLF'     | 'EMPTY'  | 'CV-33B0MZ02'(!)           = ''              | ''                 | 'CV-33B0MZ02'              |'L_VCMT104T-R56MN5'| 'NA'                           | 'IO'       | 'IND SMD 3.3U 20% 11A(VCMT104T-3R3MN5)AEC'      | 'CHIP'         | ''          | ''   | '20160614'  
 '2.2UH/9A'                     | 'SMLF'     | 'IND'    | 'CV-2290MZ02'(!)           = ''              | ''                 | 'CV-2290MZ02'              |'L_VCMT063T-2R2MN5'| '2.2UH/9A'                     | 'DISCRETE' | 'IND SMD 2.2UH 20% 9A(VCMT063T-2R2MN5)AEC'      | 'CHIP'         | ''          | ''   | '20160614'  
 '2.2UH/9A'                     | 'SMLF'     | 'EMPTY'  | 'CV-2290MZ02'(!)           = ''              | ''                 | 'CV-2290MZ02'              |'L_VCMT063T-2R2MN5'| 'NA'                           | 'IO'       | 'IND SMD 2.2UH 20% 9A(VCMT063T-2R2MN5)AEC'      | 'CHIP'         | ''          | ''   | '20160614'  
 '6.8UH/5.5A'                   | 'SMLF'     | 'IND'    | 'CV-6855MZ01'(!)           = ''              | ''                 | 'CV-6855MZ01'              |'L_VCMT063T-2R2MN5'| '6.8UH/5.5A'                   | 'DISCRETE' | 'INDSMD 6.8U 20% 5.5A(VCMT063T-6R8MN5)AEC'      | 'CHIP'         | ''          | ''   | '20160614'  
 '6.8UH/5.5A'                   | 'SMLF'     | 'EMPTY'  | 'CV-6855MZ01'(!)           = ''              | ''                 | 'CV-6855MZ01'              |'L_VCMT063T-2R2MN5'| 'NA'                           | 'IO'       | 'INDSMD 6.8U 20% 5.5A(VCMT063T-6R8MN5)AEC'      | 'CHIP'         | ''          | ''   | '20160614'  
 '600NH/26A'                    | 'SMLF'     | 'IND'    | 'CV+60R0KZ00'(!)           = 'End of Design' | 'Comp-Approve'     | 'CV+60R0KZ00'              |'L_HCUVD8095D-102KBQL_8X8'| '600NH/26A'                    | 'DISCRETE' | 'IND SMD 600NH +-10% 26A(HCUVD8095D-601K)'      | 'CHIP'         | ''          | ''   | '20160617'  
 '600NH/26A'                    | 'SMLF'     | 'EMPTY'  | 'CV+60R0KZ00'(!)           = 'End of Design' | 'Comp-Approve'     | 'CV+60R0KZ00'              |'L_HCUVD8095D-102KBQL_8X8'| 'NA'                           | 'IO'       | 'IND SMD 600NH +-10% 26A(HCUVD8095D-601K)'      | 'CHIP'         | ''          | ''   | '20160617'  
 '90NH/134A'                    | 'SMLF'     | 'IND'    | 'CVA90^0KZ01'(!)           = ''              | ''                 | 'CVA90^0KZ01'              |'L_SLA3735B'| '90NH/134A'                    | 'DISCRETE' | 'IND SMD 90NH +-10% 134A(SLA3735B-90K)'         | 'CHIP'         | ''          | ''   | '20160628'  
 '90NH/134A'                    | 'SMLF'     | 'EMPTY'  | 'CVA90^0KZ01'(!)           = ''              | ''                 | 'CVA90^0KZ01'              |'L_SLA3735B'| 'NA'                           | 'IO'       | 'IND SMD 90NH +-10% 134A(SLA3735B-90K)'         | 'CHIP'         | ''          | ''   | '20160628'  
 '180NH/60A'                    | 'SMLF'     | 'IND'    | 'CV+18^0KZ06'(!)           = 'End of Design' | 'Comp-Approve'     | 'CV+18^0KZ06'              |'L_HCUVE966490D-121'| '180NH/60A'                    | 'DISCRETE' | 'IND SMD 180NH 10% 60A(HCUVE966490D-181) '      | 'CHIP'         | ''          | ''   | '20160721'  
 '180NH/60A'                    | 'SMLF'     | 'EMPTY'  | 'CV+18^0KZ06'(!)           = 'End of Design' | 'Comp-Approve'     | 'CV+18^0KZ06'              |'L_HCUVE966490D-121'| 'NA'                           | 'IO'       | 'IND SMD 180NH 10% 60A(HCUVE966490D-181) '      | 'CHIP'         | ''          | ''   | '20160721'  
 'BLM18AG601SH1D/200MA'         | 'SMLF'     | 'IND'    | 'CX8AG601000'(!)           = ''              | ''                 | 'CX8AG601000'              |'L0603'| 'BLM18AG601SH1D/200MA'         | 'DISCRETE' | 'EMI FILTER BLM18AG601SH1D(600,200MA)'          | 'CHIP'         | ''          | ''   | '20160804'  
 'BLM18AG601SH1D/200MA'         | 'SMLF'     | 'EMPTY'  | 'CX8AG601000'(!)           = ''              | ''                 | 'CX8AG601000'              |'L0603'| 'NA'                           | 'IO'       | 'EMI FILTER BLM18AG601SH1D(600,200MA)'          | 'CHIP'         | ''          | ''   | '20160804'  
 '1UH/62A'                      | 'SMLF'     | 'IND'    | 'CV-10^0MZ11'(!)           = ''              | ''                 | 'CV-10^0MZ11'              |'L_MSE-12HZN1R0M-M1Q'| '1UH/62A'                      | 'DISCRETE' | 'IND SMD 1UH 20% 62A(MSE-12HZN1R0M-M1Q)'        | 'CHIP'         | ''          | ''   | '20160805'  
 '1UH/62A'                      | 'SMLF'     | 'EMPTY'  | 'CV-10^0MZ11'(!)           = ''              | ''                 | 'CV-10^0MZ11'              |'L_MSE-12HZN1R0M-M1Q'| 'NA'                           | 'IO'       | 'IND SMD 1UH 20% 62A(MSE-12HZN1R0M-M1Q)'        | 'CHIP'         | ''          | ''   | '20160805'  
 '1.5UH/53A'                    | 'SMLF'     | 'IND'    | 'CV-15^0MZ01'(!)           = ''              | ''                 | 'CV-15^0MZ01'              |'L_MSE-12HZN1R0M-M1Q'| '1.5UH/53A'                    | 'DISCRETE' | 'IND SMD 1.5UH 20% 53A(MSE-12HZN1R5M-M1Q)'      | 'CHIP'         | ''          | ''   | '20160805'  
 '1.5UH/53A'                    | 'SMLF'     | 'EMPTY'  | 'CV-15^0MZ01'(!)           = ''              | ''                 | 'CV-15^0MZ01'              |'L_MSE-12HZN1R0M-M1Q'| 'NA'                           | 'IO'       | 'IND SMD 1.5UH 20% 53A(MSE-12HZN1R5M-M1Q)'      | 'CHIP'         | ''          | ''   | '20160805'  
 '2.2UH/50A'                    | 'SMLF'     | 'IND'    | 'CV-22^0MZ06'(!)           = ''              | ''                 | 'CV-22^0MZ06'              |'L_MSE-12HZN1R0M-M1Q'| '2.2UH/50A'                    | 'DISCRETE' | 'IND SMD 2.2UH 20% 50A(MSE-12HZN2R2M-M1Q)'      | 'CHIP'         | ''          | ''   | '20160805'  
 '2.2UH/50A'                    | 'SMLF'     | 'EMPTY'  | 'CV-22^0MZ06'(!)           = ''              | ''                 | 'CV-22^0MZ06'              |'L_MSE-12HZN1R0M-M1Q'| 'NA'                           | 'IO'       | 'IND SMD 2.2UH 20% 50A(MSE-12HZN2R2M-M1Q)'      | 'CHIP'         | ''          | ''   | '20160805'  
 '3.3UH/45A'                    | 'SMLF'     | 'IND'    | 'CV-33^0MZ01'(!)           = ''              | ''                 | 'CV-33^0MZ01'              |'L_MSE-12HZN1R0M-M1Q'| '3.3UH/45A'                    | 'DISCRETE' | 'IND SMD 3.3UH 20% 45A(MSE-12HZN3R3M-M1Q)'      | 'CHIP'         | ''          | ''   | '20160805'  
 '3.3UH/45A'                    | 'SMLF'     | 'EMPTY'  | 'CV-33^0MZ01'(!)           = ''              | ''                 | 'CV-33^0MZ01'              |'L_MSE-12HZN1R0M-M1Q'| 'NA'                           | 'IO'       | 'IND SMD 3.3UH 20% 45A(MSE-12HZN3R3M-M1Q)'      | 'CHIP'         | ''          | ''   | '20160805'  
 '4.7UH/35A'                    | 'SMLF'     | 'IND'    | 'CV-47^0MZ00'(!)           = ''              | ''                 | 'CV-47^0MZ00'              |'L_MSE-12HZN1R0M-M1Q'| '4.7UH/35A'                    | 'DISCRETE' | 'IND SMD 4.7UH 20% 35A(MSE-12HZN4R7M-M1Q)'      | 'CHIP'         | ''          | ''   | '20160805'  
 '4.7UH/35A'                    | 'SMLF'     | 'EMPTY'  | 'CV-47^0MZ00'(!)           = ''              | ''                 | 'CV-47^0MZ00'              |'L_MSE-12HZN1R0M-M1Q'| 'NA'                           | 'IO'       | 'IND SMD 4.7UH 20% 35A(MSE-12HZN4R7M-M1Q)'      | 'CHIP'         | ''          | ''   | '20160805'  
 '1UH/19A'                      | 'SMLF'     | 'IND'    | 'CV-10J0KZ01'(!)           = ''              | ''                 | 'CV-10J0KZ01'              |'L_HCUVD8095D-102KBQL_8X8'| '1UH/19A'                      | 'DISCRETE' | 'IND SMD 1UH 10% 19A(HCUVD8095-102KQL)'         | 'CHIP'         | ''          | ''   | '20160817'  
 '1UH/19A'                      | 'SMLF'     | 'EMPTY'  | 'CV-10J0KZ01'(!)           = ''              | ''                 | 'CV-10J0KZ01'              |'L_HCUVD8095D-102KBQL_8X8'| 'NA'                           | 'IO'       | 'IND SMD 1UH 10% 19A(HCUVD8095-102KQL)'         | 'CHIP'         | ''          | ''   | '20160817'  
 '0.6UH/20A'                    | 'SMLF'     | 'IND'    | 'CV+60K0KZ01'(!)           = ''              | ''                 | 'CV+60K0KZ01'              |'L_HCUVD6595D-601KLY_6-5X6-5'| '0.6UH/20A'                    | 'DISCRETE' | 'IND SMD 0.6UH 10% 20A(HCUVD6595-601KLY)'       | 'CHIP'         | ''          | ''   | '20160817'  
 '0.6UH/20A'                    | 'SMLF'     | 'EMPTY'  | 'CV+60K0KZ01'(!)           = ''              | ''                 | 'CV+60K0KZ01'              |'L_HCUVD6595D-601KLY_6-5X6-5'| 'NA'                           | 'IO'       | 'IND SMD 0.6UH 10% 20A(HCUVD6595-601KLY)'       | 'CHIP'         | ''          | ''   | '20160817'  
 '1UH/12A'                      | 'SMLF'     | 'IND'    | 'CV-10C0KZ01'(!)           = ''              | 'End of Life'      | 'CV-10C0KZ01'              |'L_HCUVD6595D-601KLY_6-5X6-5_EOL'| '1UH/12A'                      | 'DISCRETE' | 'IND SMD 1UH 10% 12A(HCUVD6595-102KLY)'         | 'CHIP'         | ''          | ''   | '20160817'  
 '1UH/12A'                      | 'SMLF'     | 'EMPTY'  | 'CV-10C0KZ01'(!)           = ''              | 'End of Life'      | 'CV-10C0KZ01'              |'L_HCUVD6595D-601KLY_6-5X6-5_EOL'| 'NA'                           | 'IO'       | 'IND SMD 1UH 10% 12A(HCUVD6595-102KLY)'         | 'CHIP'         | ''          | ''   | '20160817'  
 'BLM15AG121SN1D/500MA'         | 'SMLF'     | 'IND'    | 'CX5AG121002'(!)           = ''              | ''                 | 'CX5AG121002'              |'L0402'| 'BLM15AG121SN1D/500MA'         | 'DISCRETE' | 'EMI FILTER BLM15AG121SN1D(120,500MA)'          | 'CHIP'         | ''          | ''   | '20141027'  
 'BLM15AG121SN1D/500MA'         | 'SMLF'     | 'EMPTY'  | 'CX5AG121002'(!)           = ''              | ''                 | 'CX5AG121002'              |'L0402'| 'NA'                           | 'IO'       | 'EMI FILTER BLM15AG121SN1D(120,500MA)'          | 'CHIP'         | ''          | ''   | '20141027'  
 '180NH/60A'                    | 'SMLF'     | 'IND'    | 'CV+18^0KZ05'(!)           = ''              | ''                 | 'CV+18^0KZ05'              |'L_HCUVE117583D_10-7X7-5'| '180NH/60A'                    | 'DISCRETE' | 'IND SMD 180NH 10% 60A(HCUVE117583D-181)'       | 'CHIP'         | ''          | ''   | '20160914'  
 '180NH/60A'                    | 'SMLF'     | 'EMPTY'  | 'CV+18^0KZ05'(!)           = ''              | ''                 | 'CV+18^0KZ05'              |'L_HCUVE117583D_10-7X7-5'| 'NA'                           | 'IO'       | 'IND SMD 180NH 10% 60A(HCUVE117583D-181)'       | 'CHIP'         | ''          | ''   | '20160914'  
 '320NH/34A'                    | 'SMLF'     | 'IND'    | 'CV+32Z0KZ00'(!)           = ''              | ''                 | 'CV+32Z0KZ00'              |'L_HCUVE117583D_10-7X7-5'| '320NH/34A'                    | 'DISCRETE' | 'IND SMD 320NH 10% 34A(HCUVE117583D-321)'       | 'CHIP'         | ''          | ''   | '20160914'  
 '320NH/34A'                    | 'SMLF'     | 'EMPTY'  | 'CV+32Z0KZ00'(!)           = ''              | ''                 | 'CV+32Z0KZ00'              |'L_HCUVE117583D_10-7X7-5'| 'NA'                           | 'IO'       | 'IND SMD 320NH 10% 34A(HCUVE117583D-321)'       | 'CHIP'         | ''          | ''   | '20160914'  
 '150NH/72A'                    | 'SMLF'     | 'IND'    | 'CV+15^0KZ11'(!)           = ''              | ''                 | 'CV+15^0KZ11'              |'L_HCUVE117583D_10-7X7-5'| '150NH/72A'                    | 'DISCRETE' | 'IND SMD 150NH 10% 72A(HCUVE117583D-151)'       | 'CHIP'         | ''          | ''   | '20160914'  
 '150NH/72A'                    | 'SMLF'     | 'EMPTY'  | 'CV+15^0KZ11'(!)           = ''              | ''                 | 'CV+15^0KZ11'              |'L_HCUVE117583D_10-7X7-5'| 'NA'                           | 'IO'       | 'IND SMD 150NH 10% 72A(HCUVE117583D-151)'       | 'CHIP'         | ''          | ''   | '20160914'  
 '120NH/90A'                    | 'SMLF'     | 'IND'    | 'CV+12^0KZ08'(!)           = ''              | ''                 | 'CV+12^0KZ08'              |'L_HCUVE117583D_10-7X7-5'| '120NH/90A'                    | 'DISCRETE' | 'IND SMD 120NH 10% 90A(HCUVE117583D-121)'       | 'CHIP'         | ''          | ''   | '20160914'  
 '120NH/90A'                    | 'SMLF'     | 'EMPTY'  | 'CV+12^0KZ08'(!)           = ''              | ''                 | 'CV+12^0KZ08'              |'L_HCUVE117583D_10-7X7-5'| 'NA'                           | 'IO'       | 'IND SMD 120NH 10% 90A(HCUVE117583D-121)'       | 'CHIP'         | ''          | ''   | '20160914'  
 'BLM21PG331SN1D'               | 'SMLF'     | 'IND'    | 'CX1PG331003'(!)           = ''              | 'End of Life'      | 'CX1PG331003'              |'L0805_EOL'| 'BLM21PG331SN1D'               | 'DISCRETE' | 'EMI FIL CHIP BLM21PG331SN1D(330,1.5A)'         | 'CHIP'         | ''          | ''   | '20111011'  
 'BLM21PG331SN1D'               | 'SMLF'     | 'EMPTY'  | 'CX1PG331003'(!)           = ''              | 'End of Life'      | 'CX1PG331003'              |'L0805_EOL'| 'NA'                           | 'IO'       | 'EMI FIL CHIP BLM21PG331SN1D(330,1.5A)'         | 'CHIP'         | ''          | ''   | '20111011'  
 '600/0.5A'                     | 'SMLF'     | 'IND'    | 'CX8EG601000'(!)           = ''              | ''                 | 'CX8EG601000'              |'L0603'| '600/0.5A'                     | 'DISCRETE' | 'EMI FILTER BLM18EG601SN1D(600,0.5A)'           | 'CHIP'         | ''          | ''   | '20161004'  
 '600/0.5A'                     | 'SMLF'     | 'EMPTY'  | 'CX8EG601000'(!)           = ''              | ''                 | 'CX8EG601000'              |'L0603'| 'NA'                           | 'IO'       | 'EMI FILTER BLM18EG601SN1D(600,0.5A)'           | 'CHIP'         | ''          | ''   | '20161004'  
 '60NH/66A'                     | 'SMLF'     | 'IND'    | 'CVA60^0KZ00'(!)           = ''              | ''                 | 'CVA60^0KZ00'              |'L_HCUVE966490D-121'| '60NH/66A'                     | 'DISCRETE' | 'IND SMD 60NH 10% 66A(HCUVE966490-600)'         | 'CHIP'         | ''          | ''   | '20161005'  
 '60NH/66A'                     | 'SMLF'     | 'EMPTY'  | 'CVA60^0KZ00'(!)           = ''              | ''                 | 'CVA60^0KZ00'              |'L_HCUVE966490D-121'| 'NA'                           | 'IO'       | 'IND SMD 60NH 10% 66A(HCUVE966490-600)'         | 'CHIP'         | ''          | ''   | '20161005'  
 '0.36UH/30A'                   | 'SMLF'     | 'IND'    | 'CV+3630MZ01'(!)           = ''              | ''                 | 'CV+3630MZ01'              |'L_MPC1055'| '0.36UH/30A'                   | 'DISCRETE' | 'IND SMD 0.36UH 20% 30A(MPC1055LR36) EU'        | 'CHIP'         | ''          | ''   | '20161006'  
 '0.36UH/30A'                   | 'SMLF'     | 'EMPTY'  | 'CV+3630MZ01'(!)           = ''              | ''                 | 'CV+3630MZ01'              |'L_MPC1055'| 'NA'                           | 'IO'       | 'IND SMD 0.36UH 20% 30A(MPC1055LR36) EU'        | 'CHIP'         | ''          | ''   | '20161006'  
 'HCB2012KF-300T60/6A'          | 'SMLF'     | 'IND'    | 'CX300T60000'(!)           = ''              | ''                 | 'CX300T60000'              |'L0805'| 'HCB2012KF-300T60/6A'          | 'DISCRETE' | 'EMI FILTER HCB2012KF-300T60(30,6A)'            | 'CHIP'         | ''          | ''   | '20161018'  
 'HCB2012KF-300T60/6A'          | 'SMLF'     | 'EMPTY'  | 'CX300T60000'(!)           = ''              | ''                 | 'CX300T60000'              |'L0805'| 'NA'                           | 'IO'       | 'EMI FILTER HCB2012KF-300T60(30,6A)'            | 'CHIP'         | ''          | ''   | '20161018'  
 '1.5UH/20.9A'                  | 'SMLF'     | 'IND'    | 'CV-15L0MZ00'(!)           = ''              | ''                 | 'CV-15L0MZ00'              |'L_VCMI136E-1R5MN54_13-45X12-6'| '1.5UH/20.9A'                  | 'DISCRETE' | 'IND SMD 1.5U 20% 20.9A(VCMI136E-1R5MN54)'      | 'CHIP'         | ''          | ''   | '20161024'  
 '1.5UH/20.9A'                  | 'SMLF'     | 'EMPTY'  | 'CV-15L0MZ00'(!)           = ''              | ''                 | 'CV-15L0MZ00'              |'L_VCMI136E-1R5MN54_13-45X12-6'| 'NA'                           | 'IO'       | 'IND SMD 1.5U 20% 20.9A(VCMI136E-1R5MN54)'      | 'CHIP'         | ''          | ''   | '20161024'  
 '0.36UH/30A'                   | 'SMLF'     | 'IND'    | 'CV+36V0MZ13'(!)           = ''              | ''                 | 'CV+36V0MZ13'              |'L_PCMB104TXA'| '0.36UH/30A'                   | 'DISCRETE' | 'IND SMD 0.36UH +-20% 30A(PCMB104T-R36MT)'      | 'CHIP'         | ''          | ''   | '20161026'  
 '0.36UH/30A'                   | 'SMLF'     | 'EMPTY'  | 'CV+36V0MZ13'(!)           = ''              | ''                 | 'CV+36V0MZ13'              |'L_PCMB104TXA'| 'NA'                           | 'IO'       | 'IND SMD 0.36UH +-20% 30A(PCMB104T-R36MT)'      | 'CHIP'         | ''          | ''   | '20161026'  
 'BLM03AX601SN1D'               | 'SMLF'     | 'IND'    | 'CX3AX601000'(!)           = ''              | ''                 | 'CX3AX601000'              |'L0201'| 'BLM03AX601SN1D'               | 'DISCRETE' | 'EMI FILTER BEAD BLM03AX601SN(600,250MA)'       | 'CHIP'         | ''          | ''   | '20161102'  
 'BLM03AX601SN1D'               | 'SMLF'     | 'EMPTY'  | 'CX3AX601000'(!)           = ''              | ''                 | 'CX3AX601000'              |'L0201'| 'NA'                           | 'IO'       | 'EMI FILTER BEAD BLM03AX601SN(600,250MA)'       | 'CHIP'         | ''          | ''   | '20161102'  
 '400NH/27A'                    | 'SMLF'     | 'IND'    | 'CV+40S0KZ01'(!)           = 'End of Design' | 'P/N Release'      | 'CV+40S0KZ01'              |'L_HCUVE966412D-221'| '400NH/27A'                    | 'DISCRETE' | 'IND SMD 400NH 10% 27A(HCUVE966412D-401)'       | 'CHIP'         | ''          | ''   | '20161104'  
 '400NH/27A'                    | 'SMLF'     | 'EMPTY'  | 'CV+40S0KZ01'(!)           = 'End of Design' | 'P/N Release'      | 'CV+40S0KZ01'              |'L_HCUVE966412D-221'| 'NA'                           | 'IO'       | 'IND SMD 400NH 10% 27A(HCUVE966412D-401)'       | 'CHIP'         | ''          | ''   | '20161104'  
 '470NH/23A'                    | 'SMLF'     | 'IND'    | 'CV+47N0KZ00'(!)           = 'End of Design' | 'Comp-Approve'     | 'CV+47N0KZ00'              |'L_HCUVE966412D-221'| '470NH/23A'                    | 'DISCRETE' | 'IND SMD 470NH 10% 23A(HCUVE966412D-471)'       | 'CHIP'         | ''          | ''   | '20161104'  
 '470NH/23A'                    | 'SMLF'     | 'EMPTY'  | 'CV+47N0KZ00'(!)           = 'End of Design' | 'Comp-Approve'     | 'CV+47N0KZ00'              |'L_HCUVE966412D-221'| 'NA'                           | 'IO'       | 'IND SMD 470NH 10% 23A(HCUVE966412D-471)'       | 'CHIP'         | ''          | ''   | '20161104'  
 '0.68UH/3.4A'                  | 'SMLF'     | 'IND'    | 'CV+6834MZ00'(!)           = ''              | ''                 | 'CV+6834MZ00'              |'L0806XB'| '0.68UH/3.4A'                  | 'DISCRETE' | 'IND SMD 0.68UH 20% 3.4A(LQM2MPNR68MGH)'        | 'CHIP'         | ''          | ''   | '20161109'  
 '0.68UH/3.4A'                  | 'SMLF'     | 'EMPTY'  | 'CV+6834MZ00'(!)           = ''              | ''                 | 'CV+6834MZ00'              |'L0806XB'| 'NA'                           | 'IO'       | 'IND SMD 0.68UH 20% 3.4A(LQM2MPNR68MGH)'        | 'CHIP'         | ''          | ''   | '20161109'  
 '300NH/37A'                    | 'SMLF'     | 'IND'    | 'CV+30^0KZ08'(!)           = 'End of Design' | 'Comp-Approve'     | 'CV+30^0KZ08'              |'L_HCUVE966412D-221'| '300NH/37A'                    | 'DISCRETE' | 'IND SMD 300NH 10% 37A(HCUVE966412D-301)'       | 'CHIP'         | ''          | ''   | '20161109'  
 '300NH/37A'                    | 'SMLF'     | 'EMPTY'  | 'CV+30^0KZ08'(!)           = 'End of Design' | 'Comp-Approve'     | 'CV+30^0KZ08'              |'L_HCUVE966412D-221'| 'NA'                           | 'IO'       | 'IND SMD 300NH 10% 37A(HCUVE966412D-301)'       | 'CHIP'         | ''          | ''   | '20161109'  
 '400NH/45A'                    | 'SMLF'     | 'IND'    | 'CV+40^0EZ01'(!)           = ''              | ''                 | 'CV+40^0EZ01'              |'L_HCUV117595'| '400NH/45A'                    | 'DISCRETE' | 'IND SMD 400NH +-15% 45A(HCUV117595-401)'       | 'CHIP'         | ''          | ''   | '20161112'  
 '400NH/45A'                    | 'SMLF'     | 'EMPTY'  | 'CV+40^0EZ01'(!)           = ''              | ''                 | 'CV+40^0EZ01'              |'L_HCUV117595'| 'NA'                           | 'IO'       | 'IND SMD 400NH +-15% 45A(HCUV117595-401)'       | 'CHIP'         | ''          | ''   | '20161112'  
 '800NH/19A'                    | 'SMLF'     | 'IND'    | 'CV+80J0KZ00'(!)           = 'End of Design' | 'Comp-Approve'     | 'CV+80J0KZ00'              |'L_HCUVD8095D-102KBQL_8X8'| '800NH/19A'                    | 'DISCRETE' | 'IND SMD 800NH 10% 19A(HCUVD8095D-801KBQL'      | 'CHIP'         | ''          | ''   | '20161116'  
 '800NH/19A'                    | 'SMLF'     | 'EMPTY'  | 'CV+80J0KZ00'(!)           = 'End of Design' | 'Comp-Approve'     | 'CV+80J0KZ00'              |'L_HCUVD8095D-102KBQL_8X8'| 'NA'                           | 'IO'       | 'IND SMD 800NH 10% 19A(HCUVD8095D-801KBQL'      | 'CHIP'         | ''          | ''   | '20161116'  
 '300NH/38A'                    | 'SMLF'     | 'IND'    | 'CV+30^0KZ09'(!)           = ''              | ''                 | 'CV+30^0KZ09'              |'L_HCUV117595'| '300NH/38A'                    | 'DISCRETE' | 'IND SMD 300NH 10% 38A(HCUV117595-301B)'        | 'CHIP'         | ''          | ''   | '20161116'  
 '300NH/38A'                    | 'SMLF'     | 'EMPTY'  | 'CV+30^0KZ09'(!)           = ''              | ''                 | 'CV+30^0KZ09'              |'L_HCUV117595'| 'NA'                           | 'IO'       | 'IND SMD 300NH 10% 38A(HCUV117595-301B)'        | 'CHIP'         | ''          | ''   | '20161116'  
 '320NH/45A'                    | 'SMLF'     | 'IND'    | 'CV+32^0EZ00'(!)           = ''              | ''                 | 'CV+32^0EZ00'              |'L_HCUV117595'| '320NH/45A'                    | 'DISCRETE' | 'IND SMD 320NH +-15% 45A(HCUV117595-321)'       | 'CHIP'         | ''          | ''   | '20161205'  
 '320NH/45A'                    | 'SMLF'     | 'EMPTY'  | 'CV+32^0EZ00'(!)           = ''              | ''                 | 'CV+32^0EZ00'              |'L_HCUV117595'| 'NA'                           | 'IO'       | 'IND SMD 320NH +-15% 45A(HCUV117595-321)'       | 'CHIP'         | ''          | ''   | '20161205'  
 '600NH/26A'                    | 'SMLF'     | 'IND'    | 'CV+60R0KZ01'(!)           = ''              | ''                 | 'CV+60R0KZ01'              |'L_HCUVD8095D-102KBQL_8X8'| '600NH/26A'                    | 'DISCRETE' | 'IND SMD 600NH 10% 26A(HCUVD8095-601K)'         | 'CHIP'         | ''          | ''   | '20161215'  
 '600NH/26A'                    | 'SMLF'     | 'EMPTY'  | 'CV+60R0KZ01'(!)           = ''              | ''                 | 'CV+60R0KZ01'              |'L_HCUVD8095D-102KBQL_8X8'| 'NA'                           | 'IO'       | 'IND SMD 600NH 10% 26A(HCUVD8095-601K)'         | 'CHIP'         | ''          | ''   | '20161215'  
 '2.2UH/5A'                     | 'SMLF'     | 'IND'    | 'CV-2250MZ00'(!)           = ''              | ''                 | 'CV-2250MZ00'              |'L_PCMB051H-2R2MS_5-4X5-2'| '2.2UH/5A'                     | 'DISCRETE' | 'IND SMD 2.2UH +-20% 5A PCMB051H-2R2MS'         | 'CHIP'         | ''          | ''   | '20161220'  
 '2.2UH/5A'                     | 'SMLF'     | 'EMPTY'  | 'CV-2250MZ00'(!)           = ''              | ''                 | 'CV-2250MZ00'              |'L_PCMB051H-2R2MS_5-4X5-2'| 'NA'                           | 'IO'       | 'IND SMD 2.2UH +-20% 5A PCMB051H-2R2MS'         | 'CHIP'         | ''          | ''   | '20161220'  
 'LBR2012T100K/150MA'           | 'SMLF'     | 'IND'    | 'CV01002KZ01'(!)           = ''              | ''                 | 'CV01002KZ01'              |'L0805_H56'| 'LBR2012T100K/150MA'           | 'DISCRETE' | 'IND SMD 10UH 10% 150MA(LBR2012T100K)'          | 'CHIP'         | ''          | ''   | '20170302'  
 'LBR2012T100K/150MA'           | 'SMLF'     | 'EMPTY'  | 'CV01002KZ01'(!)           = ''              | ''                 | 'CV01002KZ01'              |'L0805_H56'| 'NA'                           | 'IO'       | 'IND SMD 10UH 10% 150MA(LBR2012T100K)'          | 'CHIP'         | ''          | ''   | '20170302'  
 '400NH/30A'                    | 'SMLF'     | 'IND'    | 'CV+40V0KZ00'(!)           = ''              | ''                 | 'CV+40V0KZ00'              |'L_HCUVD6595D-601KLY_6-5X6-5'| '400NH/30A'                    | 'DISCRETE' | 'IND SMD 400NH 10% 30A(HCUVD6595-401K)'         | 'CHIP'         | ''          | ''   | '20170309'  
 '400NH/30A'                    | 'SMLF'     | 'EMPTY'  | 'CV+40V0KZ00'(!)           = ''              | ''                 | 'CV+40V0KZ00'              |'L_HCUVD6595D-601KLY_6-5X6-5'| 'NA'                           | 'IO'       | 'IND SMD 400NH 10% 30A(HCUVD6595-401K)'         | 'CHIP'         | ''          | ''   | '20170309'  
 'GMLB-555018-0800P-N1-QU/8A'   | 'SMLF'     | 'IND'    | 'CX555018000'(!)           = ''              | ''                 | 'CX555018000'              |'L_GMLB-555018_5-5X5'| 'GMLB-555018-0800P-N1-QU/8A'   | 'DISCRETE' | 'EMI FILTER GMLB-555018-0800P-N1(800,8A)'       | 'CHIP'         | ''          | ''   | '20170331'  
 'GMLB-555018-0800P-N1-QU/8A'   | 'SMLF'     | 'EMPTY'  | 'CX555018000'(!)           = ''              | ''                 | 'CX555018000'              |'L_GMLB-555018_5-5X5'| 'NA'                           | 'IO'       | 'EMI FILTER GMLB-555018-0800P-N1(800,8A)'       | 'CHIP'         | ''          | ''   | '20170331'  
 '10UH/4.5A'                    | 'SMLF'     | 'IND'    | 'CV01045MZ02'(!)           = ''              | ''                 | 'CV01045MZ02'              |'L_MHCI05030_5-7X5-4'| '10UH/4.5A'                    | 'DISCRETE' | 'IND SMD 10UH 20% 4.5A(MHCI05030-100M-R8)'      | 'CHIP'         | ''          | ''   | '20170421'  
 '10UH/4.5A'                    | 'SMLF'     | 'EMPTY'  | 'CV01045MZ02'(!)           = ''              | ''                 | 'CV01045MZ02'              |'L_MHCI05030_5-7X5-4'| 'NA'                           | 'IO'       | 'IND SMD 10UH 20% 4.5A(MHCI05030-100M-R8)'      | 'CHIP'         | ''          | ''   | '20170421'  
 'MPZ2012S601ATD25/2A'          | 'SMLF'     | 'IND'    | 'TX1ATD25000'(!)           = ''              | ''                 | 'TX1ATD25000'              |'L_MLZ2012'| 'MPZ2012S601ATD25/2A'          | 'DISCRETE' | 'EMI FIL MPZ2012S601ATD25(600,2A)EMS-TEA'       | 'CHIP'         | ''          | ''   | '20170614'  
 'MPZ2012S601ATD25/2A'          | 'SMLF'     | 'EMPTY'  | 'TX1ATD25000'(!)           = ''              | ''                 | 'TX1ATD25000'              |'L_MLZ2012'| 'NA'                           | 'IO'       | 'EMI FIL MPZ2012S601ATD25(600,2A)EMS-TEA'       | 'CHIP'         | ''          | ''   | '20170614'  
 'HI3312X101R-10/10A'           | 'SMLF'     | 'IND'    | 'CX2X101R000'(!)           = ''              | ''                 | 'CX2X101R000'              |'L_HI3312X101R-10_8-5X3-05'| 'HI3312X101R-10/10A'           | 'DISCRETE' | 'EMI FILTER BEAD HI3312X101R-10(100,10A)'       | 'CHIP'         | ''          | ''   | '20170628'  
 'HI3312X101R-10/10A'           | 'SMLF'     | 'EMPTY'  | 'CX2X101R000'(!)           = ''              | ''                 | 'CX2X101R000'              |'L_HI3312X101R-10_8-5X3-05'| 'NA'                           | 'IO'       | 'EMI FILTER BEAD HI3312X101R-10(100,10A)'       | 'CHIP'         | ''          | ''   | '20170628'  
 '300NH/41A'                    | 'SMLF'     | 'IND'    | 'CV+30^0KZ10'(!)           = ''              | ''                 | 'CV+30^0KZ10'              |'L_HCUV117595'| '300NH/41A'                    | 'DISCRETE' | 'IND SMD 300NH 10% 41A(HCUVE117595-301B)'       | 'CHIP'         | ''          | ''   | '20170620'  
 '300NH/41A'                    | 'SMLF'     | 'EMPTY'  | 'CV+30^0KZ10'(!)           = ''              | ''                 | 'CV+30^0KZ10'              |'L_HCUV117595'| 'NA'                           | 'IO'       | 'IND SMD 300NH 10% 41A(HCUVE117595-301B)'       | 'CHIP'         | ''          | ''   | '20170620'  
 '22NH/1.85A'                   | 'SMLF'     | 'IND'    | 'CVA2219KN01'(!)           = 'End of Design' | 'Comp-Approve'     | 'CVA2219KN01'              |'L0805'| '22NH/1.85A'                   | 'DISCRETE' | 'IND CHIP 22NH 10% 1.85A(MLH2012F22NKT)'        | 'CHIP'         | ''          | ''   | '20170731'  
 '22NH/1.85A'                   | 'SMLF'     | 'EMPTY'  | 'CVA2219KN01'(!)           = 'End of Design' | 'Comp-Approve'     | 'CVA2219KN01'              |'L0805'| 'NA'                           | 'IO'       | 'IND CHIP 22NH 10% 1.85A(MLH2012F22NKT)'        | 'CHIP'         | ''          | ''   | '20170731'  
 '22NH/2A'                      | 'SMLF'     | 'IND'    | 'CVA2220KN00'(!)           = ''              | ''                 | 'CVA2220KN00'              |'L0805'| '22NH/2A'                      | 'DISCRETE' | 'IND CHIP 22NH 10% 2A(MPB201209T-22NK-NA2'      | 'CHIP'         | ''          | ''   | '20170731'  
 '22NH/2A'                      | 'SMLF'     | 'EMPTY'  | 'CVA2220KN00'(!)           = ''              | ''                 | 'CVA2220KN00'              |'L0805'| 'NA'                           | 'IO'       | 'IND CHIP 22NH 10% 2A(MPB201209T-22NK-NA2'      | 'CHIP'         | ''          | ''   | '20170731'  
 '100NH/35A'                    | 'SMLF'     | 'IND'    | 'CV+10^0KZ02'(!)           = ''              | ''                 | 'CV+10^0KZ02'              |'L_HCB7650-101_7-6X7-5'| '100NH/35A'                    | 'DISCRETE' | 'IND SMD 100NH 10% 35A(HCB7650-101)'            | 'CHIP'         | ''          | ''   | '20170830'  
 '100NH/35A'                    | 'SMLF'     | 'EMPTY'  | 'CV+10^0KZ02'(!)           = ''              | ''                 | 'CV+10^0KZ02'              |'L_HCB7650-101_7-6X7-5'| 'NA'                           | 'IO'       | 'IND SMD 100NH 10% 35A(HCB7650-101)'            | 'CHIP'         | ''          | ''   | '20170830'  
 '1.0UH/7A'                     | 'SMLF'     | 'IND'    | 'CV-1070MZ20'(!)           = ''              | ''                 | 'CV-1070MZ20'              |'L_MMD-04BZ-1R5M-X2'| '1.0UH/7A'                     | 'DISCRETE' | 'IND SMD 1.0UH 20% 7A(MMD-04BZ-1R0M-X2Q)'       | 'CHIP'         | ''          | ''   | '20170907'  
 '1.0UH/7A'                     | 'SMLF'     | 'EMPTY'  | 'CV-1070MZ20'(!)           = ''              | ''                 | 'CV-1070MZ20'              |'L_MMD-04BZ-1R5M-X2'| 'NA'                           | 'IO'       | 'IND SMD 1.0UH 20% 7A(MMD-04BZ-1R0M-X2Q)'       | 'CHIP'         | ''          | ''   | '20170907'  
 '180NH/70A'                    | 'SMLF'     | 'IND'    | 'CV+18^0KZ09'(!)           = 'End of Design' | 'P/N Release'      | 'CV+18^0KZ09'              |'L_HCUVE768012-171_7-6X8-1'| '180NH/70A'                    | 'DISCRETE' | 'IND SMD 180NH 10% 70A(HCUVE768012D-181)'       | 'CHIP'         | ''          | ''   | '20170901'  
 '180NH/70A'                    | 'SMLF'     | 'EMPTY'  | 'CV+18^0KZ09'(!)           = 'End of Design' | 'P/N Release'      | 'CV+18^0KZ09'              |'L_HCUVE768012-171_7-6X8-1'| 'NA'                           | 'IO'       | 'IND SMD 180NH 10% 70A(HCUVE768012D-181)'       | 'CHIP'         | ''          | ''   | '20170901'  
 '180NH/74A'                    | 'SMLF'     | 'IND'    | 'CV+18^0KZ08'(!)           = ''              | ''                 | 'CV+18^0KZ08'              |'L_HCUVE768012-171_7-6X8-1'| '180NH/74A'                    | 'DISCRETE' | 'IND SMD 180NH 10% 74A(HCUVE768012-181)'        | 'CHIP'         | ''          | ''   | '20170901'  
 '180NH/74A'                    | 'SMLF'     | 'EMPTY'  | 'CV+18^0KZ08'(!)           = ''              | ''                 | 'CV+18^0KZ08'              |'L_HCUVE768012-171_7-6X8-1'| 'NA'                           | 'IO'       | 'IND SMD 180NH 10% 74A(HCUVE768012-181)'        | 'CHIP'         | ''          | ''   | '20170901'  
 '210NH/59A'                    | 'SMLF'     | 'IND'    | 'CV+21^0KZ03'(!)           = 'End of Design' | 'P/N Release'      | 'CV+21^0KZ03'              |'L_HCUVE768012-171_7-6X8-1'| '210N/59A'                     | 'DISCRETE' | 'IND SMD 210NH 10% 59A(HCUVE768012D-211)'       | 'CHIP'         | ''          | ''   | '20170901'  
 '210NH/59A'                    | 'SMLF'     | 'EMPTY'  | 'CV+21^0KZ03'(!)           = 'End of Design' | 'P/N Release'      | 'CV+21^0KZ03'              |'L_HCUVE768012-171_7-6X8-1'| 'NA'                           | 'IO'       | 'IND SMD 210NH 10% 59A(HCUVE768012D-211)'       | 'CHIP'         | ''          | ''   | '20170901'  
 '210NH/61A'                    | 'SMLF'     | 'IND'    | 'CV+21^0KZ02'(!)           = ''              | ''                 | 'CV+21^0KZ02'              |'L_HCUVE768012-171_7-6X8-1'| '210N/61A'                     | 'DISCRETE' | 'IND SMD 210NH 10% 61A(HCUVE768012-211)'        | 'CHIP'         | ''          | ''   | '20170901'  
 '210NH/61A'                    | 'SMLF'     | 'EMPTY'  | 'CV+21^0KZ02'(!)           = ''              | ''                 | 'CV+21^0KZ02'              |'L_HCUVE768012-171_7-6X8-1'| 'NA'                           | 'IO'       | 'IND SMD 210NH 10% 61A(HCUVE768012-211)'        | 'CHIP'         | ''          | ''   | '20170901'  
 '170NH/79A'                    | 'SMLF'     | 'IND'    | 'CV+17^0KZ01'(!)           = ''              | ''                 | 'CV+17^0KZ01'              |'L_HCUVE768012-171_7-6X8-1'| '170NH/79A'                    | 'DISCRETE' | 'IND SMD 170NH 10% 79A(HCUVE768012-171)'        | 'CHIP'         | ''          | ''   | '20161222'  
 '170NH/79A'                    | 'SMLF'     | 'EMPTY'  | 'CV+17^0KZ01'(!)           = ''              | ''                 | 'CV+17^0KZ01'              |'L_HCUVE768012-171_7-6X8-1'| 'NA'                           | 'IO'       | 'IND SMD 170NH 10% 79A(HCUVE768012-171)'        | 'CHIP'         | ''          | ''   | '20161222'  
 '170NH/75A'                    | 'SMLF'     | 'IND'    | 'CV+17^0KZ02'(!)           = 'End of Design' | 'Comp-Approve'     | 'CV+17^0KZ02'              |'L_HCUVE768012-171_7-6X8-1'| '170NH/75A'                    | 'DISCRETE' | 'IND SMD 170NH 10% 75A(HCUVE768012D-171)'       | 'CHIP'         | ''          | ''   | '20161222'  
 '170NH/75A'                    | 'SMLF'     | 'EMPTY'  | 'CV+17^0KZ02'(!)           = 'End of Design' | 'Comp-Approve'     | 'CV+17^0KZ02'              |'L_HCUVE768012-171_7-6X8-1'| 'NA'                           | 'IO'       | 'IND SMD 170NH 10% 75A(HCUVE768012D-171)'       | 'CHIP'         | ''          | ''   | '20161222'  
 '270NH/48A'                    | 'SMLF'     | 'IND'    | 'CV+27^0KZ16'(!)           = ''              | ''                 | 'CV+27^0KZ16'              |'L_HCUVE768012-171_7-6X8-1'| '270NH/48A'                    | 'DISCRETE' | 'IND SMD 270NH 10% 48A(HCUVE768012-271)'        | 'CHIP'         | ''          | ''   | '20161223'  
 '270NH/48A'                    | 'SMLF'     | 'EMPTY'  | 'CV+27^0KZ16'(!)           = ''              | ''                 | 'CV+27^0KZ16'              |'L_HCUVE768012-171_7-6X8-1'| 'NA'                           | 'IO'       | 'IND SMD 270NH 10% 48A(HCUVE768012-271)'        | 'CHIP'         | ''          | ''   | '20161223'  
 '270NH/46A'                    | 'SMLF'     | 'IND'    | 'CV+27^0KZ17'(!)           = ''              | ''                 | 'CV+27^0KZ17'              |'L_HCUVE768012-171_7-6X8-1'| '270NH/46A'                    | 'DISCRETE' | 'IND SMD 270NH 10% 46A(HCUVE768012D-271)'       | 'CHIP'         | ''          | ''   | '20161223'  
 '270NH/46A'                    | 'SMLF'     | 'EMPTY'  | 'CV+27^0KZ17'(!)           = ''              | ''                 | 'CV+27^0KZ17'              |'L_HCUVE768012-171_7-6X8-1'| 'NA'                           | 'IO'       | 'IND SMD 270NH 10% 46A(HCUVE768012D-271)'       | 'CHIP'         | ''          | ''   | '20161223'  
 '220NH/59A'                    | 'SMLF'     | 'IND'    | 'CV+22^0KZ21'(!)           = ''              | ''                 | 'CV+22^0KZ21'              |'L_HCUVE768012-171_7-6X8-1'| '220NH/59A'                    | 'DISCRETE' | 'IND SMD 220NH 10% 59A(HCUVE768012-221)'        | 'CHIP'         | ''          | ''   | '20161223'  
 '220NH/59A'                    | 'SMLF'     | 'EMPTY'  | 'CV+22^0KZ21'(!)           = ''              | ''                 | 'CV+22^0KZ21'              |'L_HCUVE768012-171_7-6X8-1'| 'NA'                           | 'IO'       | 'IND SMD 220NH 10% 59A(HCUVE768012-221)'        | 'CHIP'         | ''          | ''   | '20161223'  
 '220NH/57A'                    | 'SMLF'     | 'IND'    | 'CV+22^0KZ22'(!)           = 'End of Design' | 'Comp-Approve'     | 'CV+22^0KZ22'              |'L_HCUVE768012-171_7-6X8-1'| '220NH/57A'                    | 'DISCRETE' | 'IND SMD 220NH 10% 57A(HCUVE768012D-221)'       | 'CHIP'         | ''          | ''   | '20161223'  
 '220NH/57A'                    | 'SMLF'     | 'EMPTY'  | 'CV+22^0KZ22'(!)           = 'End of Design' | 'Comp-Approve'     | 'CV+22^0KZ22'              |'L_HCUVE768012-171_7-6X8-1'| 'NA'                           | 'IO'       | 'IND SMD 220NH 10% 57A(HCUVE768012D-221)'       | 'CHIP'         | ''          | ''   | '20161223'  
 '320NH/38A'                    | 'SMLF'     | 'IND'    | 'CV+32^0KZ10'(!)           = ''              | ''                 | 'CV+32^0KZ10'              |'L_HCUVE768012-171_7-6X8-1'| '320NH/38A'                    | 'DISCRETE' | 'IND SMD 320NH 10% 38A(HCUVE768012-321)'        | 'CHIP'         | ''          | ''   | '20161223'  
 '320NH/38A'                    | 'SMLF'     | 'EMPTY'  | 'CV+32^0KZ10'(!)           = ''              | ''                 | 'CV+32^0KZ10'              |'L_HCUVE768012-171_7-6X8-1'| 'NA'                           | 'IO'       | 'IND SMD 320NH 10% 38A(HCUVE768012-321)'        | 'CHIP'         | ''          | ''   | '20161223'  
 '320NH/37A'                    | 'SMLF'     | 'IND'    | 'CV+32^0KZ11'(!)           = 'End of Design' | 'Comp-Approve'     | 'CV+32^0KZ11'              |'L_HCUVE768012-171_7-6X8-1'| '320NH/37A'                    | 'DISCRETE' | 'IND SMD 320NH 10% 37A(HCUVE768012D-321)'       | 'CHIP'         | ''          | ''   | '20161223'  
 '320NH/37A'                    | 'SMLF'     | 'EMPTY'  | 'CV+32^0KZ11'(!)           = 'End of Design' | 'Comp-Approve'     | 'CV+32^0KZ11'              |'L_HCUVE768012-171_7-6X8-1'| 'NA'                           | 'IO'       | 'IND SMD 320NH 10% 37A(HCUVE768012D-321)'       | 'CHIP'         | ''          | ''   | '20161223'  
 'GMLB-160808-0030S-N8/5A'      | 'SMLF'     | 'IND'    | 'CX080030000'(!)           = ''              | ''                 | 'CX080030000'              |'L0603'| 'GMLB-160808-0030S-N8/5A'      | 'DISCRETE' | 'EMIFILT CHIP GMLB-160808-0030S-N8(30,5A)'      | 'CHIP'         | ''          | ''   | '20170921'  
 'GMLB-160808-0030S-N8/5A'      | 'SMLF'     | 'EMPTY'  | 'CX080030000'(!)           = ''              | ''                 | 'CX080030000'              |'L0603'| 'NA'                           | 'IO'       | 'EMIFILT CHIP GMLB-160808-0030S-N8(30,5A)'      | 'CHIP'         | ''          | ''   | '20170921'  
 'BLM18BB221SN1D/0.5A'          | 'SMLF'     | 'IND'    | 'CX8BB221007'(!)           = ''              | ''                 | 'CX8BB221007'              |'L0603'| 'BLM18BB221SN1D/0.5A'          | 'DISCRETE' | 'EMI FILTER CHIP BLM18BB221SN1D(10,0.5A)'       | 'CHIP'         | ''          | ''   | '20170925'  
 'BLM18BB221SN1D/0.5A'          | 'SMLF'     | 'EMPTY'  | 'CX8BB221007'(!)           = ''              | ''                 | 'CX8BB221007'              |'L0603'| 'NA'                           | 'IO'       | 'EMI FILTER CHIP BLM18BB221SN1D(10,0.5A)'       | 'CHIP'         | ''          | ''   | '20170925'  
 '330NH/28A'                    | 'SMLF'     | 'IND'    | 'CV+33T0KZ00'(!)           = ''              | ''                 | 'CV+33T0KZ00'              |'L_HCUVD6270_6-2X5-5'| '330NH/28A'                    | 'DISCRETE' | 'IND SMD 330NH 10% 28A(HCUVD6270-331QL)'        | 'CHIP'         | ''          | ''   | '20170930'  
 '330NH/28A'                    | 'SMLF'     | 'EMPTY'  | 'CV+33T0KZ00'(!)           = ''              | ''                 | 'CV+33T0KZ00'              |'L_HCUVD6270_6-2X5-5'| 'NA'                           | 'IO'       | 'IND SMD 330NH 10% 28A(HCUVD6270-331QL)'        | 'CHIP'         | ''          | ''   | '20170930'  
 '470NH/19A'                    | 'SMLF'     | 'IND'    | 'CV+47J0KZ00'(!)           = ''              | ''                 | 'CV+47J0KZ00'              |'L_HCUVD6270_6-2X5-5'| '470NH/19A'                    | 'DISCRETE' | 'IND SMD 470NH 10% 19A(HCUVD6270-471QL)'        | 'CHIP'         | ''          | ''   | '20170930'  
 '470NH/19A'                    | 'SMLF'     | 'EMPTY'  | 'CV+47J0KZ00'(!)           = ''              | ''                 | 'CV+47J0KZ00'              |'L_HCUVD6270_6-2X5-5'| 'NA'                           | 'IO'       | 'IND SMD 470NH 10% 19A(HCUVD6270-471QL)'        | 'CHIP'         | ''          | ''   | '20170930'  
 '220NH/40A'                    | 'SMLF'     | 'IND'    | 'CV+22^0KZ24'(!)           = ''              | ''                 | 'CV+22^0KZ24'              |'L_HCUVD6270_6-2X5-5'| '220NH/40A'                    | 'DISCRETE' | 'IND SMD 220NH 10% 40A(HCUVD6270-221QL)'        | 'CHIP'         | ''          | ''   | '20170930'  
 '220NH/40A'                    | 'SMLF'     | 'EMPTY'  | 'CV+22^0KZ24'(!)           = ''              | ''                 | 'CV+22^0KZ24'              |'L_HCUVD6270_6-2X5-5'| 'NA'                           | 'IO'       | 'IND SMD 220NH 10% 40A(HCUVD6270-221QL)'        | 'CHIP'         | ''          | ''   | '20170930'  
 '180NH/51A'                    | 'SMLF'     | 'IND'    | 'CV+18^0KZ10'(!)           = ''              | ''                 | 'CV+18^0KZ10'              |'L_HCUVD6270_6-2X5-5'| '180NH/51A'                    | 'DISCRETE' | 'IND SMD 180NH 10% 51A(HCUVD6270-181QL)'        | 'CHIP'         | ''          | ''   | '20170930'  
 '180NH/51A'                    | 'SMLF'     | 'EMPTY'  | 'CV+18^0KZ10'(!)           = ''              | ''                 | 'CV+18^0KZ10'              |'L_HCUVD6270_6-2X5-5'| 'NA'                           | 'IO'       | 'IND SMD 180NH 10% 51A(HCUVD6270-181QL)'        | 'CHIP'         | ''          | ''   | '20170930'  
 '150NH/61A'                    | 'SMLF'     | 'IND'    | 'CV+15^0KZ14'(!)           = ''              | ''                 | 'CV+15^0KZ14'              |'L_HCUVD6270_6-2X5-7'| '150NH/61A'                    | 'DISCRETE' | 'IND SMD 150NH 10% 61A(HCUVD6270-151QL)'        | 'CHIP'         | ''          | ''   | '20170930'  
 '150NH/61A'                    | 'SMLF'     | 'EMPTY'  | 'CV+15^0KZ14'(!)           = ''              | ''                 | 'CV+15^0KZ14'              |'L_HCUVD6270_6-2X5-7'| 'NA'                           | 'IO'       | 'IND SMD 150NH 10% 61A(HCUVD6270-151QL)'        | 'CHIP'         | ''          | ''   | '20170930'  
 'BLM18BA100SN1D/500MA'         | 'SMLF'     | 'IND'    | 'CX8BA100001'(!)           = ''              | ''                 | 'CX8BA100001'              |'L0603'| 'BLM18BA100SN1D/500MA'         | 'DISCRETE' | 'EMI FILTER BLM18BA100SN1D(10,500MA)'           | 'CHIP'         | ''          | ''   | '20171002'  
 'BLM18BA100SN1D/500MA'         | 'SMLF'     | 'EMPTY'  | 'CX8BA100001'(!)           = ''              | ''                 | 'CX8BA100001'              |'L0603'| 'NA'                           | 'IO'       | 'EMI FILTER BLM18BA100SN1D(10,500MA)'           | 'CHIP'         | ''          | ''   | '20171002'  
 '0.15UH/26A'                   | 'SMLF'     | 'IND'    | 'CV+15R0MZ00'(!)           = ''              | ''                 | 'CV+15R0MZ00'              |'L_PCMS063T_6-6X6-6'| '0.15UH/26A'                   | 'DISCRETE' | 'IND SMD 0.15UH 20% 26A(PCMS063T-R15MN1R)'      | 'CHIP'         | ''          | ''   | '20171017'  
 '0.15UH/26A'                   | 'SMLF'     | 'EMPTY'  | 'CV+15R0MZ00'(!)           = ''              | ''                 | 'CV+15R0MZ00'              |'L_PCMS063T_6-6X6-6'| 'NA'                           | 'IO'       | 'IND SMD 0.15UH 20% 26A(PCMS063T-R15MN1R)'      | 'CHIP'         | ''          | ''   | '20171017'  
 'HCB1608KF-221T25/2.5A'        | 'SMLF'     | 'IND'    | 'CX221T25000'(!)           = ''              | ''                 | 'CX221T25000'              |'L0603'| 'HCB1608KF-221T25/2.5A'        | 'DISCRETE' | 'EMI FILTER HCB1608KF-221T25(220,2.5A)'         | 'CHIP'         | ''          | ''   | '20171027'  
 'HCB1608KF-221T25/2.5A'        | 'SMLF'     | 'EMPTY'  | 'CX221T25000'(!)           = ''              | ''                 | 'CX221T25000'              |'L0603'| 'NA'                           | 'IO'       | 'EMI FILTER HCB1608KF-221T25(220,2.5A)'         | 'CHIP'         | ''          | ''   | '20171027'  
 '150NH/86A'                    | 'SMLF'     | 'IND'    | 'CV+15^0KZ15'(!)           = 'End of Design' | 'Comp-Approve'     | 'CV+15^0KZ15'              |'L_HCUVE768012-171_7-6X8-1'| '150NH/86A'                    | 'DISCRETE' | 'IND SMD 150NH 10% 86A(HCUVE768012D-151)'       | 'CHIP'         | ''          | ''   | '20171030'  
 '150NH/86A'                    | 'SMLF'     | 'EMPTY'  | 'CV+15^0KZ15'(!)           = 'End of Design' | 'Comp-Approve'     | 'CV+15^0KZ15'              |'L_HCUVE768012-171_7-6X8-1'| 'NA'                           | 'IO'       | 'IND SMD 150NH 10% 86A(HCUVE768012D-151)'       | 'CHIP'         | ''          | ''   | '20171030'  
 '180NH/64A'                    | 'SMLF'     | 'IND'    | 'CV+18^0KZ07'(!)           = ''              | ''                 | 'CV+18^0KZ07'              |'L_HCUVE966490D-121'| '180NH/64A'                    | 'DISCRETE' | 'IND SMD 180NH 10% 64A(HCUVE966490-181)'        | 'CHIP'         | ''          | ''   | '20171103'  
 '180NH/64A'                    | 'SMLF'     | 'EMPTY'  | 'CV+18^0KZ07'(!)           = ''              | ''                 | 'CV+18^0KZ07'              |'L_HCUVE966490D-121'| 'NA'                           | 'IO'       | 'IND SMD 180NH 10% 64A(HCUVE966490-181)'        | 'CHIP'         | ''          | ''   | '20171103'  
 '0.47UH/9.5A'                  | 'SMLF'     | 'IND'    | 'CV+4795MZ03'(!)           = ''              | ''                 | 'CV+4795MZ03'              |'L_CMLS041B_4-4X4-2'| '0.47UH/9.5A'                  | 'DISCRETE' | 'IND SMD 0.47UH20%9.5A(CMME041B-R47MS)'         | 'CHIP'         | ''          | ''   | '20171107'  
 '0.47UH/9.5A'                  | 'SMLF'     | 'EMPTY'  | 'CV+4795MZ03'(!)           = ''              | ''                 | 'CV+4795MZ03'              |'L_CMLS041B_4-4X4-2'| 'NA'                           | 'IO'       | 'IND SMD 0.47UH20%9.5A(CMME041B-R47MS)'         | 'CHIP'         | ''          | ''   | '20171107'  
 '1UH/6.5A'                     | 'SMLF'     | 'IND'    | 'CV-1065MZ03'(!)           = ''              | ''                 | 'CV-1065MZ03'              |'L_MMD-05AEN1R0M-X2Q_5-15X5-18'| '1UH/6.5A'                     | 'DISCRETE' | 'IND SMD 1UH20%6.5A,MMD-05AEN1R0M-X2Q'          | 'CHIP'         | ''          | ''   | '20171107'  
 '1UH/6.5A'                     | 'SMLF'     | 'EMPTY'  | 'CV-1065MZ03'(!)           = ''              | ''                 | 'CV-1065MZ03'              |'L_MMD-05AEN1R0M-X2Q_5-15X5-18'| 'NA'                           | 'IO'       | 'IND SMD 1UH20%6.5A,MMD-05AEN1R0M-X2Q'          | 'CHIP'         | ''          | ''   | '20171107'  
 '90NH/114A'                    | 'SMLF'     | 'IND'    | 'CVA90^0KZ02'(!)           = 'End of Design' | 'Comp-Approve'     | 'CVA90^0KZ02'              |'L_HCUVE966490D-121'| '90NH/114A'                    | 'DISCRETE' | 'IND SMD 90NH 10% 114A(HCUVE966490D-900)'       | 'CHIP'         | ''          | ''   | '20171109'  
 '90NH/114A'                    | 'SMLF'     | 'EMPTY'  | 'CVA90^0KZ02'(!)           = 'End of Design' | 'Comp-Approve'     | 'CVA90^0KZ02'              |'L_HCUVE966490D-121'| 'NA'                           | 'IO'       | 'IND SMD 90NH 10% 114A(HCUVE966490D-900)'       | 'CHIP'         | ''          | ''   | '20171109'  
 '210NH/50A'                    | 'SMLF'     | 'IND'    | 'CV+21^0KZ01'(!)           = ''              | ''                 | 'CV+21^0KZ01'              |'L_HCUVE966490D-121'| '210NH/50A'                    | 'DISCRETE' | 'IND SMD 210NH 10% 50A(HCUVE966490-211'         | 'CHIP'         | ''          | ''   | '20171109'  
 '210NH/50A'                    | 'SMLF'     | 'EMPTY'  | 'CV+21^0KZ01'(!)           = ''              | ''                 | 'CV+21^0KZ01'              |'L_HCUVE966490D-121'| 'NA'                           | 'IO'       | 'IND SMD 210NH 10% 50A(HCUVE966490-211'         | 'CHIP'         | ''          | ''   | '20171109'  
 '700NH/50A'                    | 'SMLF'     | 'IND'    | 'CV+70^0KZ00'(!)           = ''              | ''                 | 'CV+70^0KZ00'              |'L_HCUVD1115_11X8'| '700NH/50A'                    | 'DISCRETE' | 'IND SMD 700NH 10% 50A(HCUVD1115-701)'          | 'CHIP'         | ''          | ''   | '20171109'  
 '700NH/50A'                    | 'SMLF'     | 'EMPTY'  | 'CV+70^0KZ00'(!)           = ''              | ''                 | 'CV+70^0KZ00'              |'L_HCUVD1115_11X8'| 'NA'                           | 'IO'       | 'IND SMD 700NH 10% 50A(HCUVD1115-701)'          | 'CHIP'         | ''          | ''   | '20171109'  
 '100NH/16A'                    | 'SMLF'     | 'IND'    | 'CV+10G0MZ08'(!)           = ''              | ''                 | 'CV+10G0MZ08'              |'L_MSI-500505-R10M-E_4-5X4-7'| '100NH/16A'                    | 'DISCRETE' | 'IND SMD 100NH 20% 16A(MSI-500505-R10M-E'       | 'CHIP'         | ''          | ''   | '20171113'  
 '100NH/16A'                    | 'SMLF'     | 'EMPTY'  | 'CV+10G0MZ08'(!)           = ''              | ''                 | 'CV+10G0MZ08'              |'L_MSI-500505-R10M-E_4-5X4-7'| 'NA'                           | 'IO'       | 'IND SMD 100NH 20% 16A(MSI-500505-R10M-E'       | 'CHIP'         | ''          | ''   | '20171113'  
 '200NH/52A'                    | 'SMLF'     | 'IND'    | 'CV+20^0KZ03'(!)           = ''              | ''                 | 'CV+20^0KZ03'              |'L_HCUVD6595-201_6-5X6-6'| '200NH/52A'                    | 'DISCRETE' | 'IND SMD 200NH 10% 52A(HCUVD6595-201)'          | 'CHIP'         | ''          | ''   | '20171114'  
 '200NH/52A'                    | 'SMLF'     | 'EMPTY'  | 'CV+20^0KZ03'(!)           = ''              | ''                 | 'CV+20^0KZ03'              |'L_HCUVD6595-201_6-5X6-6'| 'NA'                           | 'IO'       | 'IND SMD 200NH 10% 52A(HCUVD6595-201)'          | 'CHIP'         | ''          | ''   | '20171114'  
 '0.22UH/64A'                   | 'SMLF'     | 'IND'    | 'CV+22^0KZ25'(!)           = ''              | ''                 | 'CV+22^0KZ25'              |'L_HCUVE117512D'| '0.22UH/64A'                   | 'DISCRETE' | 'IIND SMD 0.22UH 10% 64A(MSI-110812V-R22K'      | 'CHIP'         | ''          | ''   | '20171114'  
 '0.22UH/64A'                   | 'SMLF'     | 'EMPTY'  | 'CV+22^0KZ25'(!)           = ''              | ''                 | 'CV+22^0KZ25'              |'L_HCUVE117512D'| 'NA'                           | 'IO'       | 'IIND SMD 0.22UH 10% 64A(MSI-110812V-R22K'      | 'CHIP'         | ''          | ''   | '20171114'  
 '0.27UH/51A'                   | 'SMLF'     | 'IND'    | 'CV+27^0KZ18'(!)           = ''              | ''                 | 'CV+27^0KZ18'              |'L_HCUVE117512D'| '0.27UH/51A'                   | 'DISCRETE' | 'IND SMD 0.27UH 10% 51A(MSI-110812V-R27K'       | 'CHIP'         | ''          | ''   | '20171114'  
 '0.27UH/51A'                   | 'SMLF'     | 'EMPTY'  | 'CV+27^0KZ18'(!)           = ''              | ''                 | 'CV+27^0KZ18'              |'L_HCUVE117512D'| 'NA'                           | 'IO'       | 'IND SMD 0.27UH 10% 51A(MSI-110812V-R27K'       | 'CHIP'         | ''          | ''   | '20171114'  
 '0.25UH/56A'                   | 'SMLF'     | 'IND'    | 'CV+25^0MZ00'(!)           = ''              | ''                 | 'CV+25^0MZ00'              |'L_HCUVE117512D'| '0.25UH/56A'                   | 'DISCRETE' | 'IND SMD 0.25UH 20% 56A(MSI-110812V-R25M'       | 'CHIP'         | ''          | ''   | '20171114'  
 '0.25UH/56A'                   | 'SMLF'     | 'EMPTY'  | 'CV+25^0MZ00'(!)           = ''              | ''                 | 'CV+25^0MZ00'              |'L_HCUVE117512D'| 'NA'                           | 'IO'       | 'IND SMD 0.25UH 20% 56A(MSI-110812V-R25M'       | 'CHIP'         | ''          | ''   | '20171114'  
 '0.4UH/35A'                    | 'SMLF'     | 'IND'    | 'CV+40^0KZ03'(!)           = ''              | ''                 | 'CV+40^0KZ03'              |'L_HCUVE117512D'| '0.4UH/35A'                    | 'DISCRETE' | 'IND SMD 0.4UH 10% 35A(MSI-110812V-R40K'        | 'CHIP'         | ''          | ''   | '20171114'  
 '0.4UH/35A'                    | 'SMLF'     | 'EMPTY'  | 'CV+40^0KZ03'(!)           = ''              | ''                 | 'CV+40^0KZ03'              |'L_HCUVE117512D'| 'NA'                           | 'IO'       | 'IND SMD 0.4UH 10% 35A(MSI-110812V-R40K'        | 'CHIP'         | ''          | ''   | '20171114'  
 '0.6UH/21A'                    | 'SMLF'     | 'IND'    | 'CV+60L0MZ00'(!)           = ''              | ''                 | 'CV+60L0MZ00'              |'L_HCUVE117512D'| '0.6UH/21A'                    | 'DISCRETE' | 'IND SMD 0.6UH 20% 21A(MSI-110812V-R60M'        | 'CHIP'         | ''          | ''   | '20171114'  
 '0.6UH/21A'                    | 'SMLF'     | 'EMPTY'  | 'CV+60L0MZ00'(!)           = ''              | ''                 | 'CV+60L0MZ00'              |'L_HCUVE117512D'| 'NA'                           | 'IO'       | 'IND SMD 0.6UH 20% 21A(MSI-110812V-R60M'        | 'CHIP'         | ''          | ''   | '20171114'  
 '0.47UH/29A'                   | 'SMLF'     | 'IND'    | 'CV+47U0KZ00'(!)           = ''              | ''                 | 'CV+47U0KZ00'              |'L_HCUVE117512D'| '0.47UH/29A'                   | 'DISCRETE' | 'IND SMD 0.47UH 10% 29A(MSI-110812V-R47K'       | 'CHIP'         | ''          | ''   | '20171114'  
 '0.47UH/29A'                   | 'SMLF'     | 'EMPTY'  | 'CV+47U0KZ00'(!)           = ''              | ''                 | 'CV+47U0KZ00'              |'L_HCUVE117512D'| 'NA'                           | 'IO'       | 'IND SMD 0.47UH 10% 29A(MSI-110812V-R47K'       | 'CHIP'         | ''          | ''   | '20171114'  
 '0.32UH/43A'                   | 'SMLF'     | 'IND'    | 'CV+32^0KZ12'(!)           = ''              | ''                 | 'CV+32^0KZ12'              |'L_HCUVE117512D'| '0.32UH/43A'                   | 'DISCRETE' | 'IND SMD 0.32UH 10% 43A(MSI-110812V-R32K'       | 'CHIP'         | ''          | ''   | '20171114'  
 '0.32UH/43A'                   | 'SMLF'     | 'EMPTY'  | 'CV+32^0KZ12'(!)           = ''              | ''                 | 'CV+32^0KZ12'              |'L_HCUVE117512D'| 'NA'                           | 'IO'       | 'IND SMD 0.32UH 10% 43A(MSI-110812V-R32K'       | 'CHIP'         | ''          | ''   | '20171114'  
 '70NH/48A'                     | 'SMLF'     | 'IND'    | 'CVA70^0MZ03'(!)           = ''              | ''                 | 'CVA70^0MZ03'              |'L_MSI-600607_6-1X6'| '70NH/48A'                     | 'DISCRETE' | 'IND SMD 70NH 20% 48A(MSI-600607-70NM'          | 'CHIP'         | ''          | ''   | '20171114'  
 '70NH/48A'                     | 'SMLF'     | 'EMPTY'  | 'CVA70^0MZ03'(!)           = ''              | ''                 | 'CVA70^0MZ03'              |'L_MSI-600607_6-1X6'| 'NA'                           | 'IO'       | 'IND SMD 70NH 20% 48A(MSI-600607-70NM'          | 'CHIP'         | ''          | ''   | '20171114'  
 '80NH/40A'                     | 'SMLF'     | 'IND'    | 'CVA80^0MZ02'(!)           = ''              | ''                 | 'CVA80^0MZ02'              |'L_HCBS5265_5-2X5-2'| '80NH/40A'                     | 'DISCRETE' | 'IND SMD 80NH 20% 40A(MSI-500507-80NM'          | 'CHIP'         | ''          | ''   | '20171114'  
 '80NH/40A'                     | 'SMLF'     | 'EMPTY'  | 'CVA80^0MZ02'(!)           = ''              | ''                 | 'CVA80^0MZ02'              |'L_HCBS5265_5-2X5-2'| 'NA'                           | 'IO'       | 'IND SMD 80NH 20% 40A(MSI-500507-80NM'          | 'CHIP'         | ''          | ''   | '20171114'  
 '0.1UH/13A'                    | 'SMLF'     | 'IND'    | 'CV+10D0MZ00'(!)           = ''              | ''                 | 'CV+10D0MZ00'              |'L_MSI-400405_4X4-2'| '0.1UH/13A'                    | 'DISCRETE' | 'IND SMD 0.1UH 20% 13A(MSI-400405-R10M'         | 'CHIP'         | ''          | ''   | '20171114'  
 '0.1UH/13A'                    | 'SMLF'     | 'EMPTY'  | 'CV+10D0MZ00'(!)           = ''              | ''                 | 'CV+10D0MZ00'              |'L_MSI-400405_4X4-2'| 'NA'                           | 'IO'       | 'IND SMD 0.1UH 20% 13A(MSI-400405-R10M'         | 'CHIP'         | ''          | ''   | '20171114'  
 '150NH/75A'                    | 'SMLF'     | 'IND'    | 'CV+15^0KZ10'(!)           = 'End of Design' | 'Comp-Approve'     | 'CV+15^0KZ10'              |'L_HCUVE117512D_10-7X7-7'| '150NH/75A'                    | 'DISCRETE' | 'IND SMD 150NH 10% 75A(HCUVE117512D-151)'       | 'CHIP'         | ''          | ''   | '20160608'  
 '150NH/75A'                    | 'SMLF'     | 'EMPTY'  | 'CV+15^0KZ10'(!)           = 'End of Design' | 'Comp-Approve'     | 'CV+15^0KZ10'              |'L_HCUVE117512D_10-7X7-7'| 'NA'                           | 'IO'       | 'IND SMD 150NH 10% 75A(HCUVE117512D-151)'       | 'CHIP'         | ''          | ''   | '20160608'  
 '180NH/76A'                    | 'SMLF'     | 'IND'    | 'CV+18^0KZ11'(!)           = 'End of Design' | 'Comp-Approve'     | 'CV+18^0KZ11'              |'L_HCUVE117512D_10-7X7-7'| '180NH/76A'                    | 'DISCRETE' | 'IND SMD 180NH 10% 76A(HCUVE117512D-181)'       | 'CHIP'         | ''          | ''   | '20171117'  
 '180NH/76A'                    | 'SMLF'     | 'EMPTY'  | 'CV+18^0KZ11'(!)           = 'End of Design' | 'Comp-Approve'     | 'CV+18^0KZ11'              |'L_HCUVE117512D_10-7X7-7'| 'NA'                           | 'IO'       | 'IND SMD 180NH 10% 76A(HCUVE117512D-181)'       | 'CHIP'         | ''          | ''   | '20171117'  
 '220NH/0.2A'                   | 'SMLF'     | 'IND'    | 'CV+2202GZ00'(!)           = ''              | ''                 | 'CV+2202GZ00'              |'L0603'| '220NH/0.2A'                   | 'DISCRETE' | 'IND SMD 220NH 2% 0.2A(LQW18ASR22G0ZD)AEC'      | 'CHIP'         | ''          | ''   | '20171120'  
 '220NH/0.2A'                   | 'SMLF'     | 'EMPTY'  | 'CV+2202GZ00'(!)           = ''              | ''                 | 'CV+2202GZ00'              |'L0603'| 'NA'                           | 'IO'       | 'IND SMD 220NH 2% 0.2A(LQW18ASR22G0ZD)AEC'      | 'CHIP'         | ''          | ''   | '20171120'  
 '1.0UH/3A'                     | 'SMLF'     | 'IND'    | 'CV-1030MZ01'(!)           = ''              | ''                 | 'CV-1030MZ01'              |'L_MLV-YT12N_2-5X2'| '1.0UH/3A'                     | 'DISCRETE' | 'IND SMD 1.0UH +-20% 3A MLV-YT12N1R0M-O1Q'      | 'CHIP'         | ''          | ''   | '20171121'  
 '1.0UH/3A'                     | 'SMLF'     | 'EMPTY'  | 'CV-1030MZ01'(!)           = ''              | ''                 | 'CV-1030MZ01'              |'L_MLV-YT12N_2-5X2'| 'NA'                           | 'IO'       | 'IND SMD 1.0UH +-20% 3A MLV-YT12N1R0M-O1Q'      | 'CHIP'         | ''          | ''   | '20171121'  
 '47UH/75MA'                    | 'SMLF'     | 'IND'    | 'CV04701KN03'(!)           = ''              | ''                 | 'CV04701KN03'              |'L0805_H62'| '47UH/75MA'                    | 'DISCRETE' | 'IND CHIP 47UH 10% 75MA(LB R2012T470K)'         | 'CHIP'         | ''          | ''   | '20171121'  
 '47UH/75MA'                    | 'SMLF'     | 'EMPTY'  | 'CV04701KN03'(!)           = ''              | ''                 | 'CV04701KN03'              |'L0805_H62'| 'NA'                           | 'IO'       | 'IND CHIP 47UH 10% 75MA(LB R2012T470K)'         | 'CHIP'         | ''          | ''   | '20171121'  
 'FCM1608KF-102T06/0.6A'        | 'SMLF'     | 'IND'    | 'CX102T06000'(!)           = 'End of Design' | 'Comp-Approve'     | 'CX102T06000'              |'L0603'| 'FCM1608KF-102T06/0.6A'        | 'DISCRETE' | 'EMI FILTER FCM1608KF-102T06(1000,0.6A)'        | 'CHIP'         | ''          | ''   | '20171123'  
 'FCM1608KF-102T06/0.6A'        | 'SMLF'     | 'EMPTY'  | 'CX102T06000'(!)           = 'End of Design' | 'Comp-Approve'     | 'CX102T06000'              |'L0603'| 'NA'                           | 'IO'       | 'EMI FILTER FCM1608KF-102T06(1000,0.6A)'        | 'CHIP'         | ''          | ''   | '20171123'  
 '0.16UH/84A'                   | 'SMLF'     | 'IND'    | 'CV+16^0KZ00'(!)           = ''              | ''                 | 'CV+16^0KZ00'              |'L_HCUVE117512D_10-7X7-7'| '0.16UH/84A'                   | 'DISCRETE' | 'IND SMD 0.16UH 10% 84A(MSI-110812V-R16K'       | 'CHIP'         | ''          | ''   | '20171204'  
 '0.16UH/84A'                   | 'SMLF'     | 'EMPTY'  | 'CV+16^0KZ00'(!)           = ''              | ''                 | 'CV+16^0KZ00'              |'L_HCUVE117512D_10-7X7-7'| 'NA'                           | 'IO'       | 'IND SMD 0.16UH 10% 84A(MSI-110812V-R16K'       | 'CHIP'         | ''          | ''   | '20171204'  
 '0.17UH/78A'                   | 'SMLF'     | 'IND'    | 'CV+17^0KZ03'(!)           = ''              | ''                 | 'CV+17^0KZ03'              |'L_HCUVE117512D_10-7X7-7'| '0.17UH/78A'                   | 'DISCRETE' | 'IND SMD 0.17UH 10% 78A(MSI-110812V-R17K'       | 'CHIP'         | ''          | ''   | '20171204'  
 '0.17UH/78A'                   | 'SMLF'     | 'EMPTY'  | 'CV+17^0KZ03'(!)           = ''              | ''                 | 'CV+17^0KZ03'              |'L_HCUVE117512D_10-7X7-7'| 'NA'                           | 'IO'       | 'IND SMD 0.17UH 10% 78A(MSI-110812V-R17K'       | 'CHIP'         | ''          | ''   | '20171204'  
 '0.18UH/76A'                   | 'SMLF'     | 'IND'    | 'CV+18^0KZ12'(!)           = ''              | ''                 | 'CV+18^0KZ12'              |'L_HCUVE117512D_10-7X7-7'| '0.18UH/76A'                   | 'DISCRETE' | 'IND SMD 0.18UH 10% 76A(MSI-110812V-R18K'       | 'CHIP'         | ''          | ''   | '20171204'  
 '0.18UH/76A'                   | 'SMLF'     | 'EMPTY'  | 'CV+18^0KZ12'(!)           = ''              | ''                 | 'CV+18^0KZ12'              |'L_HCUVE117512D_10-7X7-7'| 'NA'                           | 'IO'       | 'IND SMD 0.18UH 10% 76A(MSI-110812V-R18K'       | 'CHIP'         | ''          | ''   | '20171204'  
 '0.2UH/69A'                    | 'SMLF'     | 'IND'    | 'CV+20^0KZ05'(!)           = ''              | ''                 | 'CV+20^0KZ05'              |'L_HCUVE117512D'| '0.2UH/69A'                    | 'DISCRETE' | 'IND SMD 0.2UH 10% 69A(MSI-110812V-R20K'        | 'CHIP'         | ''          | ''   | '20171204'  
 '0.2UH/69A'                    | 'SMLF'     | 'EMPTY'  | 'CV+20^0KZ05'(!)           = ''              | ''                 | 'CV+20^0KZ05'              |'L_HCUVE117512D'| 'NA'                           | 'IO'       | 'IND SMD 0.2UH 10% 69A(MSI-110812V-R20K'        | 'CHIP'         | ''          | ''   | '20171204'  
 'BLM15PD121SN1D/1300MA'        | 'SMLF'     | 'IND'    | 'CX5PD121000'(!)           = ''              | ''                 | 'CX5PD121000'              |'L0402'| 'BLM15PD121SN1D/1300MA'        | 'DISCRETE' | 'EMI FILTER BLM15PD121SN1D(120OHM,1300MA)'      | 'CHIP'         | ''          | ''   | '20171207'  
 'BLM15PD121SN1D/1300MA'        | 'SMLF'     | 'EMPTY'  | 'CX5PD121000'(!)           = ''              | ''                 | 'CX5PD121000'              |'L0402'| 'NA'                           | 'IO'       | 'EMI FILTER BLM15PD121SN1D(120OHM,1300MA)'      | 'CHIP'         | ''          | ''   | '20171207'  
 'BLM18KG331SN1D/1.7A'          | 'SMLF'     | 'IND'    | 'CX8KG331000'(!)           = ''              | ''                 | 'CX8KG331000'              |'L0603'| 'BLM18KG331SN1D/1.7A'          | 'DISCRETE' | 'EMI FILTER BLM18KG331SN1D(330,1.7A)'           | 'CHIP'         | ''          | ''   | '20171212'  
 'BLM18KG331SN1D/1.7A'          | 'SMLF'     | 'EMPTY'  | 'CX8KG331000'(!)           = ''              | ''                 | 'CX8KG331000'              |'L0603'| 'NA'                           | 'IO'       | 'EMI FILTER BLM18KG331SN1D(330,1.7A)'           | 'CHIP'         | ''          | ''   | '20171212'  
 'BLM31KN471SN1L/4A'            | 'SMLF'     | 'IND'    | 'CX1KN471000'(!)           = ''              | ''                 | 'CX1KN471000'              |'L1206XB'| 'BLM31KN471SN1L/4A'            | 'DISCRETE' | 'EMI FILTER BEAD BLM31KN471SN1L(470,4A)'        | 'CHIP'         | ''          | ''   | '20171213'  
 'BLM31KN471SN1L/4A'            | 'SMLF'     | 'EMPTY'  | 'CX1KN471000'(!)           = ''              | ''                 | 'CX1KN471000'              |'L1206XB'| 'NA'                           | 'IO'       | 'EMI FILTER BEAD BLM31KN471SN1L(470,4A)'        | 'CHIP'         | ''          | ''   | '20171213'  
 '300NH/36A'                    | 'SMLF'     | 'IND'    | 'CV+30^0KZ13'(!)           = ''              | ''                 | 'CV+30^0KZ13'              |'L_HCUVD6595-201_6-5X6-6'| '300NH/36A'                    | 'DISCRETE' | 'IND SMD 300NH 10% 36A(HCUVD6595D-301LY)'       | 'CHIP'         | ''          | ''   | '20171218'  
 '300NH/36A'                    | 'SMLF'     | 'EMPTY'  | 'CV+30^0KZ13'(!)           = ''              | ''                 | 'CV+30^0KZ13'              |'L_HCUVD6595-201_6-5X6-6'| 'NA'                           | 'IO'       | 'IND SMD 300NH 10% 36A(HCUVD6595D-301LY)'       | 'CHIP'         | ''          | ''   | '20171218'  
 '110NH/124A'                   | 'SMLF'     | 'IND'    | 'CV+11^0KZ00'(!)           = ''              | ''                 | 'CV+11^0KZ00'              |'L_HCUVE117512D_10-7X7-7'| '110NH/124A'                   | 'DISCRETE' | 'IND SMD 110NH 10% 124A(HCUVE117512D-111)'      | 'CHIP'         | ''          | ''   | '20171222'  
 '110NH/124A'                   | 'SMLF'     | 'EMPTY'  | 'CV+11^0KZ00'(!)           = ''              | ''                 | 'CV+11^0KZ00'              |'L_HCUVE117512D_10-7X7-7'| 'NA'                           | 'IO'       | 'IND SMD 110NH 10% 124A(HCUVE117512D-111)'      | 'CHIP'         | ''          | ''   | '20171222'  
 '0.17UH/64A'                   | 'SMLF'     | 'IND'    | 'CV+17^0KZ04'(!)           = ''              | ''                 | 'CV+17^0KZ04'              |'L_HCUVE768012-171_7-6X8-1'| '0.17UH/64A'                   | 'DISCRETE' | 'IND SMD 0.17UH 10% 64A(MSI-800812V-R17K'       | 'CHIP'         | ''          | ''   | '20171226'  
 '0.17UH/64A'                   | 'SMLF'     | 'EMPTY'  | 'CV+17^0KZ04'(!)           = ''              | ''                 | 'CV+17^0KZ04'              |'L_HCUVE768012-171_7-6X8-1'| 'NA'                           | 'IO'       | 'IND SMD 0.17UH 10% 64A(MSI-800812V-R17K'       | 'CHIP'         | ''          | ''   | '20171226'  
 '0.22UH/48A'                   | 'SMLF'     | 'IND'    | 'CV+22^0KZ26'(!)           = ''              | ''                 | 'CV+22^0KZ26'              |'L_HCUVE768012-171_7-6X8-1'| '0.22UH/48A'                   | 'DISCRETE' | 'IND SMD 0.22UH 10% 48A(MSI-800812V-R22K'       | 'CHIP'         | ''          | ''   | '20171226'  
 '0.22UH/48A'                   | 'SMLF'     | 'EMPTY'  | 'CV+22^0KZ26'(!)           = ''              | ''                 | 'CV+22^0KZ26'              |'L_HCUVE768012-171_7-6X8-1'| 'NA'                           | 'IO'       | 'IND SMD 0.22UH 10% 48A(MSI-800812V-R22K'       | 'CHIP'         | ''          | ''   | '20171226'  
 '0.32UH/31A'                   | 'SMLF'     | 'IND'    | 'CV+32W0KZ00'(!)           = ''              | ''                 | 'CV+32W0KZ00'              |'L_HCUVE768012-171_7-6X8-1'| '0.32UH/31A'                   | 'DISCRETE' | 'IND SMD 0.32UH 10% 31A(MSI-800812V-R32K'       | 'CHIP'         | ''          | ''   | '20171226'  
 '0.32UH/31A'                   | 'SMLF'     | 'EMPTY'  | 'CV+32W0KZ00'(!)           = ''              | ''                 | 'CV+32W0KZ00'              |'L_HCUVE768012-171_7-6X8-1'| 'NA'                           | 'IO'       | 'IND SMD 0.32UH 10% 31A(MSI-800812V-R32K'       | 'CHIP'         | ''          | ''   | '20171226'  
 '1UH/7A'                       | 'SMLF'     | 'IND'    | 'CV-1070MZ08'(!)           = ''              | ''                 | 'CV-1070MZ08'              |'L_CMME053T_4-5X4-7'| '1UH/7A'                       | 'DISCRETE' | 'IND SMD 1UH +-20% 7A(PCMB053T--1R0MS)'         | 'CHIP'         | ''          | ''   | '20180119'  
 '1UH/7A'                       | 'SMLF'     | 'EMPTY'  | 'CV-1070MZ08'(!)           = ''              | ''                 | 'CV-1070MZ08'              |'L_CMME053T_4-5X4-7'| 'NA'                           | 'IO'       | 'IND SMD 1UH +-20% 7A(PCMB053T--1R0MS)'         | 'CHIP'         | ''          | ''   | '20180119'  
 '200UH/45A'                    | 'SMLF'     | 'IND'    | 'CV120^0KZ00'(!)           = ''              | 'End of Life'      | 'CV120^0KZ00'              |'L_HCUVD6270_6-2X5-5_EOL'| '200UH/45A'                    | 'DISCRETE' | 'IND SMD 200UH 10% 45A(HCUVD6270-201QL)'        | 'CHIP'         | ''          | ''   | '20180119'  
 '200UH/45A'                    | 'SMLF'     | 'EMPTY'  | 'CV120^0KZ00'(!)           = ''              | 'End of Life'      | 'CV120^0KZ00'              |'L_HCUVD6270_6-2X5-5_EOL'| 'NA'                           | 'IO'       | 'IND SMD 200UH 10% 45A(HCUVD6270-201QL)'        | 'CHIP'         | ''          | ''   | '20180119'  
 '220/2.2A'                     | 'SMLF'     | 'IND'    | 'CX8KG221000'(!)           = 'End of Design' | 'Comp-Approve'     | 'CX8KG221000'              |'L0603'| '220/2.2A'                     | 'DISCRETE' | 'EMI FILTER BLM18KG221SN1D(220,2.2A)'           | 'CHIP'         | ''          | ''   | '20180129'  
 '220/2.2A'                     | 'SMLF'     | 'EMPTY'  | 'CX8KG221000'(!)           = 'End of Design' | 'Comp-Approve'     | 'CX8KG221000'              |'L0603'| 'NA'                           | 'IO'       | 'EMI FILTER BLM18KG221SN1D(220,2.2A)'           | 'CHIP'         | ''          | ''   | '20180129'  
 '0.33UH/10A'                   | 'SMLF'     | 'IND'    | 'CV+33A0MZ02'(!)           = ''              | ''                 | 'CV+33A0MZ02'              |'L_MMD-06AEE_6-86X6-47'| '0.33UH/10A'                   | 'DISCRETE' | 'IND SMD 0.33UH 20% 10A MMD-06AEER33M-X5Q'      | 'CHIP'         | ''          | ''   | '20180205'  
 '0.33UH/10A'                   | 'SMLF'     | 'EMPTY'  | 'CV+33A0MZ02'(!)           = ''              | ''                 | 'CV+33A0MZ02'              |'L_MMD-06AEE_6-86X6-47'| 'NA'                           | 'IO'       | 'IND SMD 0.33UH 20% 10A MMD-06AEER33M-X5Q'      | 'CHIP'         | ''          | ''   | '20180205'  
 '0.68UH/13A'                   | 'SMLF'     | 'IND'    | 'CV+68D0MZ00'(!)           = ''              | ''                 | 'CV+68D0MZ00'              |'L_MMD-05AEH_5-49X5-18'| '0.68UH/13A'                   | 'DISCRETE' | 'IND SMD 0.68U,13A,20%(MMD-05AEHR68M-T1Q)'      | 'CHIP'         | ''          | ''   | '20180205'  
 '0.68UH/13A'                   | 'SMLF'     | 'EMPTY'  | 'CV+68D0MZ00'(!)           = ''              | ''                 | 'CV+68D0MZ00'              |'L_MMD-05AEH_5-49X5-18'| 'NA'                           | 'IO'       | 'IND SMD 0.68U,13A,20%(MMD-05AEHR68M-T1Q)'      | 'CHIP'         | ''          | ''   | '20180205'  
 'BLM15BA330SN1D/300MA'         | 'SMLF'     | 'IND'    | 'CX5BA330001'(!)           = ''              | ''                 | 'CX5BA330001'              |'L0402'| 'BLM15BA330SN1D/300MA'         | 'DISCRETE' | 'EMI FILTER BLM15BA330SN1D(33,300MA)0402'       | 'CHIP'         | ''          | ''   | '20180208'  
 'BLM15BA330SN1D/300MA'         | 'SMLF'     | 'EMPTY'  | 'CX5BA330001'(!)           = ''              | ''                 | 'CX5BA330001'              |'L0402'| 'NA'                           | 'IO'       | 'EMI FILTER BLM15BA330SN1D(33,300MA)0402'       | 'CHIP'         | ''          | ''   | '20180208'  
 'FCM1608VF-301T05/0.5A'        | 'SMLF'     | 'IND'    | 'CX301T05000'(!)           = ''              | ''                 | 'CX301T05000'              |'L0603'| 'FCM1608VF-301T05/0.5A'        | 'DISCRETE' | 'EMI FILTER FCM1608VF-301T05(300,0.5A)'         | 'CHIP'         | ''          | ''   | '20180312'  
 'FCM1608VF-301T05/0.5A'        | 'SMLF'     | 'EMPTY'  | 'CX301T05000'(!)           = ''              | ''                 | 'CX301T05000'              |'L0603'| 'NA'                           | 'IO'       | 'EMI FILTER FCM1608VF-301T05(300,0.5A)'         | 'CHIP'         | ''          | ''   | '20180312'  
 '220NH/75A'                    | 'SMLF'     | 'IND'    | 'CV+22^0KZ27'(!)           = 'End of Design' | 'Comp-Approve'     | 'CV+22^0KZ27'              |'L_HCUVE1112D-221_10-7X7-5'| '220NH/75A'                    | 'DISCRETE' | 'IND SMD 220NH 10% 75A(HCUVE1112D-221)'         | 'CHIP'         | ''          | ''   | '20180312'  
 '220NH/75A'                    | 'SMLF'     | 'EMPTY'  | 'CV+22^0KZ27'(!)           = 'End of Design' | 'Comp-Approve'     | 'CV+22^0KZ27'              |'L_HCUVE1112D-221_10-7X7-5'| 'NA'                           | 'IO'       | 'IND SMD 220NH 10% 75A(HCUVE1112D-221)'         | 'CHIP'         | ''          | ''   | '20180312'  
 '400NH/41A'                    | 'SMLF'     | 'IND'    | 'CV+40^0KZ04'(!)           = 'End of Design' | 'Comp-Release Qty' | 'CV+40^0KZ04'              |'L_HCUVE1112D-221_10-7X7-5'| '400NH/41A'                    | 'DISCRETE' | 'IND SMD 400NH 10% 41A(HCUVE1112D-401)'         | 'CHIP'         | ''          | ''   | '20180312'  
 '400NH/41A'                    | 'SMLF'     | 'EMPTY'  | 'CV+40^0KZ04'(!)           = 'End of Design' | 'Comp-Release Qty' | 'CV+40^0KZ04'              |'L_HCUVE1112D-221_10-7X7-5'| 'NA'                           | 'IO'       | 'IND SMD 400NH 10% 41A(HCUVE1112D-401)'         | 'CHIP'         | ''          | ''   | '20180312'  
 'MMZ1608R601AT/0.5A'           | 'SMLF'     | 'IND'    | 'CX08R601000'(!)           = 'End of Design' | 'End of Life'      | 'CX08R601000'              |'L0603_EOL'| 'MMZ1608R601AT/0.5A'           | 'DISCRETE' | 'EMI FILTER CHIP MMZ1608R601AT(600,0.5A)'       | 'CHIP'         | ''          | ''   | '20180313'  
 'MMZ1608R601AT/0.5A'           | 'SMLF'     | 'EMPTY'  | 'CX08R601000'(!)           = 'End of Design' | 'End of Life'      | 'CX08R601000'              |'L0603_EOL'| 'NA'                           | 'IO'       | 'EMI FILTER CHIP MMZ1608R601AT(600,0.5A)'       | 'CHIP'         | ''          | ''   | '20180313'  
 '4.7UH/210MA'                  | 'SMLF'     | 'IND'    | 'CV-4703MN13'(!)           = ''              | ''                 | 'CV-4703MN13'              |'L0806'| '4.7UH/210MA'                  | 'DISCRETE' | 'IND SMD 4.7UH,+-20%,210MA,LB2016T4R7M'         | 'CHIP'         | ''          | ''   | '20180313'  
 '4.7UH/210MA'                  | 'SMLF'     | 'EMPTY'  | 'CV-4703MN13'(!)           = ''              | ''                 | 'CV-4703MN13'              |'L0806'| 'NA'                           | 'IO'       | 'IND SMD 4.7UH,+-20%,210MA,LB2016T4R7M'         | 'CHIP'         | ''          | ''   | '20180313'  
 '3.3UH/2A'                     | 'SMLF'     | 'IND'    | 'CV-3320MZ05'(!)           = ''              | ''                 | 'CV-3320MZ05'              |'L_MLPS-4015W-3R3M-F_4X4'| '3.3UH/2A'                     | 'DISCRETE' | 'IND SMD 3.3UH 20% 2A(MLPS-4015W-3R3M-F)'       | 'CHIP'         | ''          | ''   | '20180313'  
 '3.3UH/2A'                     | 'SMLF'     | 'EMPTY'  | 'CV-3320MZ05'(!)           = ''              | ''                 | 'CV-3320MZ05'              |'L_MLPS-4015W-3R3M-F_4X4'| 'NA'                           | 'IO'       | 'IND SMD 3.3UH 20% 2A(MLPS-4015W-3R3M-F)'       | 'CHIP'         | ''          | ''   | '20180313'  
 '15N/250MA'                    | 'SMLF'     | 'IND'    | 'CVA1503JN77'(!)           = ''              | ''                 | 'CVA1503JN77'              |'L0402'| '15N/250MA'                    | 'DISCRETE' | 'IND CHIP 15N +-5% 250MA CLH1005T-15NJ-S'       | 'CHIP'         | ''          | ''   | '20180320'  
 '15N/250MA'                    | 'SMLF'     | 'EMPTY'  | 'CVA1503JN77'(!)           = ''              | ''                 | 'CVA1503JN77'              |'L0402'| 'NA'                           | 'IO'       | 'IND CHIP 15N +-5% 250MA CLH1005T-15NJ-S'       | 'CHIP'         | ''          | ''   | '20180320'  
 '22NH/350MA'                   | 'SMLF'     | 'IND'    | 'CVA2204JN02'(!)           = ''              | ''                 | 'CVA2204JN02'              |'L0402'| '22NH/350MA'                   | 'DISCRETE' | 'IND CHIP 22NH 5% 350MA(LQG15HS22NJ02D)'        | 'CHIP'         | ''          | ''   | '20180322'  
 '22NH/350MA'                   | 'SMLF'     | 'EMPTY'  | 'CVA2204JN02'(!)           = ''              | ''                 | 'CVA2204JN02'              |'L0402'| 'NA'                           | 'IO'       | 'IND CHIP 22NH 5% 350MA(LQG15HS22NJ02D)'        | 'CHIP'         | ''          | ''   | '20180322'  
 '1UH/7A'                       | 'SMLF'     | 'IND'    | 'CV-1070MZ07'(!)           = 'End of Design' | 'Comp-Release Qty' | 'CV-1070MZ07'              |'L_CMLE053T_4-85X4-7'| '1UH/7A'                       | 'DISCRETE' | 'IND SMD 1UH +-20% 7A(PIMB053T-1R0MS)'          | 'CHIP'         | ''          | ''   | '20180323'  
 '1UH/7A'                       | 'SMLF'     | 'EMPTY'  | 'CV-1070MZ07'(!)           = 'End of Design' | 'Comp-Release Qty' | 'CV-1070MZ07'              |'L_CMLE053T_4-85X4-7'| 'NA'                           | 'IO'       | 'IND SMD 1UH +-20% 7A(PIMB053T-1R0MS)'          | 'CHIP'         | ''          | ''   | '20180323'  
 '58NH/83A'                     | 'SMLF'     | 'IND'    | 'CVA58^0KZ00'(!)           = ''              | ''                 | 'CVA58^0KZ00'              |'L_FP0805R1-R06-R_6-5X7-49'| '58NH/83A'                     | 'DISCRETE' | 'IND SMD 58NH +-10% 83A(FP0805R1-R06-R)'        | 'CHIP'         | ''          | ''   | '20170705'  
 '58NH/83A'                     | 'SMLF'     | 'EMPTY'  | 'CVA58^0KZ00'(!)           = ''              | ''                 | 'CVA58^0KZ00'              |'L_FP0805R1-R06-R_6-5X7-49'| 'NA'                           | 'IO'       | 'IND SMD 58NH +-10% 83A(FP0805R1-R06-R)'        | 'CHIP'         | ''          | ''   | '20170705'  
 'GMLB-201209-0220P-N8/3A'      | 'SMLF'     | 'IND'    | 'CX090220001'(!)           = ''              | ''                 | 'CX090220001'              |'L0805_H44'| 'GMLB-201209-0220P-N8/3A'      | 'DISCRETE' | 'EMI FILTER GMLB-201209-0220P-N8(220,3A)'       | 'CHIP'         | ''          | ''   | '20180331'  
 'GMLB-201209-0220P-N8/3A'      | 'SMLF'     | 'EMPTY'  | 'CX090220001'(!)           = ''              | ''                 | 'CX090220001'              |'L0805_H44'| 'NA'                           | 'IO'       | 'EMI FILTER GMLB-201209-0220P-N8(220,3A)'       | 'CHIP'         | ''          | ''   | '20180331'  
 'BLM18HE102SN1D/0.6A'          | 'SMLF'     | 'IND'    | 'CX8HE102000'(!)           = ''              | ''                 | 'CX8HE102000'              |'L0603'| 'BLM18HE102SN1D/0.6A'          | 'DISCRETE' | 'EMI FILTER BLM18HE102SN1D(1000,0.6A)'          | 'CHIP'         | ''          | ''   | '20180402'  
 'BLM18HE102SN1D/0.6A'          | 'SMLF'     | 'EMPTY'  | 'CX8HE102000'(!)           = ''              | ''                 | 'CX8HE102000'              |'L0603'| 'NA'                           | 'IO'       | 'EMI FILTER BLM18HE102SN1D(1000,0.6A)'          | 'CHIP'         | ''          | ''   | '20180402'  
 '200NH/45A'                    | 'SMLF'     | 'IND'    | 'CV+20^0KZ06'(!)           = ''              | ''                 | 'CV+20^0KZ06'              |'L_HCUVD6270_6-2X5-5'| '200NH/45A'                    | 'DISCRETE' | 'IND SMD 200NH 10% 45A(HCUVD6270-201QL)'        | 'CHIP'         | ''          | ''   | '20180409'  
 '200NH/45A'                    | 'SMLF'     | 'EMPTY'  | 'CV+20^0KZ06'(!)           = ''              | ''                 | 'CV+20^0KZ06'              |'L_HCUVD6270_6-2X5-5'| 'NA'                           | 'IO'       | 'IND SMD 200NH 10% 45A(HCUVD6270-201QL)'        | 'CHIP'         | ''          | ''   | '20180409'  
 '72NH/65A'                     | 'SMLF'     | 'IND'    | 'CVA72^0KZ01'(!)           = ''              | ''                 | 'CVA72^0KZ01'              |'L_FP0805R1-R06-R_6-5X7-49'| '72NH/65A'                     | 'DISCRETE' | 'IND SMD 72NH +-10% 65A(FP0805R1-R07-R)'        | 'CHIP'         | ''          | ''   | '20180418'  
 '72NH/65A'                     | 'SMLF'     | 'EMPTY'  | 'CVA72^0KZ01'(!)           = ''              | ''                 | 'CVA72^0KZ01'              |'L_FP0805R1-R06-R_6-5X7-49'| 'NA'                           | 'IO'       | 'IND SMD 72NH +-10% 65A(FP0805R1-R07-R)'        | 'CHIP'         | ''          | ''   | '20180418'  
 '47UH/4.4A'                    | 'SMLF'     | 'IND'    | 'CV04744MZ00'(!)           = ''              | ''                 | 'CV04744MZ00'              |'L_MSCDRI104RXA'| '47UH/4.4A'                    | 'DISCRETE' | 'IND SMD 47UH+-20%4.4A(MSCDRI-104R-470M)'       | 'CHIP'         | ''          | ''   | '20150731'  
 '47UH/4.4A'                    | 'SMLF'     | 'EMPTY'  | 'CV04744MZ00'(!)           = ''              | ''                 | 'CV04744MZ00'              |'L_MSCDRI104RXA'| 'NA'                           | 'IO'       | 'IND SMD 47UH+-20%4.4A(MSCDRI-104R-470M)'       | 'CHIP'         | ''          | ''   | '20150731'  
 'MLB-160808-0100P-N1A/3A'      | 'SMLF'     | 'IND'    | 'CX00100P009'(!)           = ''              | ''                 | 'CX00100P009'              |'L0603'| 'MLB-160808-0100P-N1A/3A'      | 'DISCRETE' | 'EMI FILTER MLB-160808-0100P-N1A(100,3A)'       | 'CHIP'         | ''          | ''   | '20180507'  
 'MLB-160808-0100P-N1A/3A'      | 'SMLF'     | 'EMPTY'  | 'CX00100P009'(!)           = ''              | ''                 | 'CX00100P009'              |'L0603'| 'NA'                           | 'IO'       | 'EMI FILTER MLB-160808-0100P-N1A(100,3A)'       | 'CHIP'         | ''          | ''   | '20180507'  
 '470NH/38A'                    | 'SMLF'     | 'IND'    | 'CV+47^0KZ07'(!)           = 'End of Design' | 'Comp-Release Qty' | 'CV+47^0KZ07'              |'L_HCUVD8095D-102KBQL_8X8'| '470NH/38A'                    | 'DISCRETE' | 'IND SMD 470NH 10% 38A(HCUVD8095D-471QL)'       | 'CHIP'         | ''          | ''   | '20180511'  
 '470NH/38A'                    | 'SMLF'     | 'EMPTY'  | 'CV+47^0KZ07'(!)           = 'End of Design' | 'Comp-Release Qty' | 'CV+47^0KZ07'              |'L_HCUVD8095D-102KBQL_8X8'| 'NA'                           | 'IO'       | 'IND SMD 470NH 10% 38A(HCUVD8095D-471QL)'       | 'CHIP'         | ''          | ''   | '20180511'  
 'BLM15AG221SN1D/300MA'         | 'SMLF'     | 'IND'    | 'CX5AG221104'(!)           = ''              | ''                 | 'CX5AG221104'              |'L0402'| 'BLM15AG221SN1D/300MA'         | 'DISCRETE' | 'EMI FILTER BLM15AG221SN1D(220,300MA)'          | 'CHIP'         | ''          | ''   | '20180413'  
 'BLM15AG221SN1D/300MA'         | 'SMLF'     | 'EMPTY'  | 'CX5AG221104'(!)           = ''              | ''                 | 'CX5AG221104'              |'L0402'| 'NA'                           | 'IO'       | 'EMI FILTER BLM15AG221SN1D(220,300MA)'          | 'CHIP'         | ''          | ''   | '20180413'  
 '400NH/40A'                    | 'SMLF'     | 'IND'    | 'CV+40^0KZ02'(!)           = 'End of Design' | 'Comp-Approve'     | 'CV+40^0KZ02'              |'L_HCUVD8095D-102KBQL_8X8'| '400NH/40A'                    | 'DISCRETE' | 'IND SMD 400NH 10% 40A(HCUVD8095D-401QL)'       | 'CHIP'         | ''          | ''   | '20171012'  
 '400NH/40A'                    | 'SMLF'     | 'EMPTY'  | 'CV+40^0KZ02'(!)           = 'End of Design' | 'Comp-Approve'     | 'CV+40^0KZ02'              |'L_HCUVD8095D-102KBQL_8X8'| 'NA'                           | 'IO'       | 'IND SMD 400NH 10% 40A(HCUVD8095D-401QL)'       | 'CHIP'         | ''          | ''   | '20171012'  
 '0.56UH/36.5A'                 | 'SMLF'     | 'IND'    | 'CV+56^0KZ00'(!)           = ''              | ''                 | 'CV+56^0KZ00'              |'L_PCMB103T-2R2MS_10-1X10'| '0.56UH/36.5A'                 | 'DISCRETE' | 'IND SMD 0.56UH 10% 36.5A(CMME103T-R56MS)'      | 'CHIP'         | ''          | ''   | '20180719'  
 '0.56UH/36.5A'                 | 'SMLF'     | 'EMPTY'  | 'CV+56^0KZ00'(!)           = ''              | ''                 | 'CV+56^0KZ00'              |'L_PCMB103T-2R2MS_10-1X10'| 'NA'                           | 'IO'       | 'IND SMD 0.56UH 10% 36.5A(CMME103T-R56MS)'      | 'CHIP'         | ''          | ''   | '20180719'  
 '120NH/133A'                   | 'SMLF'     | 'IND'    | 'CV+12^0KZ10'(!)           = ''              | ''                 | 'CV+12^0KZ10'              |'L_HCUVE117512D_10-7X7-7'| '120NH/133A'                   | 'DISCRETE' | 'IND SMD 120NH 10% 133A(HCUVE117512D-121)'      | 'CHIP'         | ''          | ''   | '20180719'  
 '120NH/133A'                   | 'SMLF'     | 'EMPTY'  | 'CV+12^0KZ10'(!)           = ''              | ''                 | 'CV+12^0KZ10'              |'L_HCUVE117512D_10-7X7-7'| 'NA'                           | 'IO'       | 'IND SMD 120NH 10% 133A(HCUVE117512D-121)'      | 'CHIP'         | ''          | ''   | '20180719'  
 '68NH/300MA'                   | 'SMLF'     | 'IND'    | 'CVA6803JN12'(!)           = ''              | ''                 | 'CVA6803JN12'              |'L0603'| '68NH/300MA'                   | 'DISCRETE' | 'IND SMD 68NH +-5%300MA(LQG18HN68NJ00D)'        | 'CHIP'         | ''          | ''   | '20180719'  
 '68NH/300MA'                   | 'SMLF'     | 'EMPTY'  | 'CVA6803JN12'(!)           = ''              | ''                 | 'CVA6803JN12'              |'L0603'| 'NA'                           | 'IO'       | 'IND SMD 68NH +-5%300MA(LQG18HN68NJ00D)'        | 'CHIP'         | ''          | ''   | '20180719'  
 '10UH/20A'                     | 'SMLF'     | 'IND'    | 'CV010K0MZ00'(!)           = ''              | ''                 | 'CV010K0MZ00'              |'L_CMLB177T_16-3X17-15'| '10UH/20A'                     | 'DISCRETE' | 'IND SMD 10UH 20% 20A(CMLB177T-100MS)'          | 'CHIP'         | ''          | ''   | '20180723'  
 '10UH/20A'                     | 'SMLF'     | 'EMPTY'  | 'CV010K0MZ00'(!)           = ''              | ''                 | 'CV010K0MZ00'              |'L_CMLB177T_16-3X17-15'| 'NA'                           | 'IO'       | 'IND SMD 10UH 20% 20A(CMLB177T-100MS)'          | 'CHIP'         | ''          | ''   | '20180723'  
 '130NH/111A'                   | 'SMLF'     | 'IND'    | 'CV+13^0KZ00'(!)           = ''              | ''                 | 'CV+13^0KZ00'              |'L_HCME107512-131_10X7-5'| '130NH/111A'                   | 'DISCRETE' | 'IND SMD 130NH 10% 111A(HCME107512-131)'        | 'CHIP'         | ''          | ''   | '20180726'  
 '130NH/111A'                   | 'SMLF'     | 'EMPTY'  | 'CV+13^0KZ00'(!)           = ''              | ''                 | 'CV+13^0KZ00'              |'L_HCME107512-131_10X7-5'| 'NA'                           | 'IO'       | 'IND SMD 130NH 10% 111A(HCME107512-131)'        | 'CHIP'         | ''          | ''   | '20180726'  
 '130NH/106A'                   | 'SMLF'     | 'IND'    | 'CV+13^0KZ01'(!)           = 'End of Design' | 'Comp-Approve'     | 'CV+13^0KZ01'              |'L_HCME107512-131_10X7-5'| '130NH/106A'                   | 'DISCRETE' | 'IND SMD 130NH 10% 106A(HCME107512D-131)'       | 'CHIP'         | ''          | ''   | '20180726'  
 '130NH/106A'                   | 'SMLF'     | 'EMPTY'  | 'CV+13^0KZ01'(!)           = 'End of Design' | 'Comp-Approve'     | 'CV+13^0KZ01'              |'L_HCME107512-131_10X7-5'| 'NA'                           | 'IO'       | 'IND SMD 130NH 10% 106A(HCME107512D-131)'       | 'CHIP'         | ''          | ''   | '20180726'  
 '130NH/106A'                   | 'SMLF'     | 'IND'    | 'CV+13^0KZ03'(!)           = 'End of Design' | 'P/N Release'      | 'CV+13^0KZ03'              |'L_HCME967512D-131_9-6X7-5'| '130NH/106A'                   | 'DISCRETE' | 'IND SMD 130NH 10% 106A(HCME967512D-131)'       | 'CHIP'         | ''          | ''   | '20180726'  
 '130NH/106A'                   | 'SMLF'     | 'EMPTY'  | 'CV+13^0KZ03'(!)           = 'End of Design' | 'P/N Release'      | 'CV+13^0KZ03'              |'L_HCME967512D-131_9-6X7-5'| 'NA'                           | 'IO'       | 'IND SMD 130NH 10% 106A(HCME967512D-131)'       | 'CHIP'         | ''          | ''   | '20180726'  
 '130NH/111A'                   | 'SMLF'     | 'IND'    | 'CV+13^0KZ02'(!)           = ''              | ''                 | 'CV+13^0KZ02'              |'L_HCME967512D-131_9-6X7-5'| '130NH/111A'                   | 'DISCRETE' | 'IND SMD 130NH 10% 111A(HCME967512-131)'        | 'CHIP'         | ''          | ''   | '20180726'  
 '130NH/111A'                   | 'SMLF'     | 'EMPTY'  | 'CV+13^0KZ02'(!)           = ''              | ''                 | 'CV+13^0KZ02'              |'L_HCME967512D-131_9-6X7-5'| 'NA'                           | 'IO'       | 'IND SMD 130NH 10% 111A(HCME967512-131)'        | 'CHIP'         | ''          | ''   | '20180726'  
 '0.33UH/14A'                   | 'SMLF'     | 'IND'    | 'CV+33E0MZ00'(!)           = ''              | ''                 | 'CV+33E0MZ00'              |'L_CMME053T_4-5X4-7'| '0.33UH/14A'                   | 'DISCRETE' | 'IND SMD 0.33UH 20% 14A(CMME053T-R33MS'         | 'CHIP'         | ''          | ''   | '20180810'  
 '0.33UH/14A'                   | 'SMLF'     | 'EMPTY'  | 'CV+33E0MZ00'(!)           = ''              | ''                 | 'CV+33E0MZ00'              |'L_CMME053T_4-5X4-7'| 'NA'                           | 'IO'       | 'IND SMD 0.33UH 20% 14A(CMME053T-R33MS'         | 'CHIP'         | ''          | ''   | '20180810'  
 '0.47UH/12A'                   | 'SMLF'     | 'IND'    | 'CV+47C0MZ00'(!)           = ''              | ''                 | 'CV+47C0MZ00'              |'L_CMME053T_4-5X4-7'| '0.47UH/12A'                   | 'DISCRETE' | 'IND SMD 0.47UH 20% 12A(PCMB053T-R47MS)'        | 'CHIP'         | ''          | ''   | '20180815'  
 '0.47UH/12A'                   | 'SMLF'     | 'EMPTY'  | 'CV+47C0MZ00'(!)           = ''              | ''                 | 'CV+47C0MZ00'              |'L_CMME053T_4-5X4-7'| 'NA'                           | 'IO'       | 'IND SMD 0.47UH 20% 12A(PCMB053T-R47MS)'        | 'CHIP'         | ''          | ''   | '20180815'  
 '6.8UH/3A'                     | 'SMLF'     | 'IND'    | 'CV-6830MZ01'(!)           = ''              | ''                 | 'CV-6830MZ01'              |'L_CMME053T_4-5X4-7'| '6.8UH/3A'                     | 'DISCRETE' | 'IND SMD 6.8UH +-20% 3A PIMB053T-6R8MS'         | 'CHIP'         | ''          | ''   | '20180815'  
 '6.8UH/3A'                     | 'SMLF'     | 'EMPTY'  | 'CV-6830MZ01'(!)           = ''              | ''                 | 'CV-6830MZ01'              |'L_CMME053T_4-5X4-7'| 'NA'                           | 'IO'       | 'IND SMD 6.8UH +-20% 3A PIMB053T-6R8MS'         | 'CHIP'         | ''          | ''   | '20180815'  
 '1.5UH/3A'                     | 'SMLF'     | 'IND'    | 'CV-1530MN00'(!)           = ''              | ''                 | 'CV-1530MN00'              |'L_DFP252012TF_2-5X2'| '1.5UH/3A'                     | 'DISCRETE' | 'IND CHIP 1.5UH +-20% 3A(SRN2512-1R5M)'         | 'CHIP'         | ''          | ''   | '20180816'  
 '1.5UH/3A'                     | 'SMLF'     | 'EMPTY'  | 'CV-1530MN00'(!)           = ''              | ''                 | 'CV-1530MN00'              |'L_DFP252012TF_2-5X2'| 'NA'                           | 'IO'       | 'IND CHIP 1.5UH +-20% 3A(SRN2512-1R5M)'         | 'CHIP'         | ''          | ''   | '20180816'  
 'BK1005HS102-T/300MA'          | 'SMLF'     | 'IND'    | 'CX5HS102108'(!)           = 'End of Design' | 'End of Life'      | 'CX5HS102108'              |'L0402_EOL'| 'BK1005HS102-T/300MA'          | 'DISCRETE' | 'EMI FILTER BK1005HS102-T(1000,300MA)'          | 'CHIP'         | ''          | ''   | '20180816'  
 'BK1005HS102-T/300MA'          | 'SMLF'     | 'EMPTY'  | 'CX5HS102108'(!)           = 'End of Design' | 'End of Life'      | 'CX5HS102108'              |'L0402_EOL'| 'NA'                           | 'IO'       | 'EMI FILTER BK1005HS102-T(1000,300MA)'          | 'CHIP'         | ''          | ''   | '20180816'  
 '1UH/4.4A'                     | 'SMLF'     | 'IND'    | 'CV-1044MZ03'(!)           = ''              | ''                 | 'CV-1044MZ03'              |'L_BDHH002520101R0ME1_2-5X2'| '1UH/4.4A'                     | 'DISCRETE' | 'IND SMD 1UH,20% 4.4A(BDHH002520101R0ME1)'      | 'CHIP'         | ''          | ''   | '20180817'  
 '1UH/4.4A'                     | 'SMLF'     | 'EMPTY'  | 'CV-1044MZ03'(!)           = ''              | ''                 | 'CV-1044MZ03'              |'L_BDHH002520101R0ME1_2-5X2'| 'NA'                           | 'IO'       | 'IND SMD 1UH,20% 4.4A(BDHH002520101R0ME1)'      | 'CHIP'         | ''          | ''   | '20180817'  
 '1000H/0.22A'                  | 'SMLF'     | 'IND'    | 'CX3HR102000'(!)           = 'End of Design' | 'Comp-Approve'     | 'CX3HR102000'              |'L0201'| '1000H/0.22A'                  | 'DISCRETE' | 'EMI FILTER BEAD BK0603HR102-T(1000,0.22A'      | 'CHIP'         | ''          | ''   | '20180822'  
 '1000H/0.22A'                  | 'SMLF'     | 'EMPTY'  | 'CX3HR102000'(!)           = 'End of Design' | 'Comp-Approve'     | 'CX3HR102000'              |'L0201'| 'NA'                           | 'IO'       | 'EMI FILTER BEAD BK0603HR102-T(1000,0.22A'      | 'CHIP'         | ''          | ''   | '20180822'  
 '4.7UH/4A'                     | 'SMLF'     | 'IND'    | 'CV-4740MZ03'(!)           = ''              | ''                 | 'CV-4740MZ03'              |'L_CMME053T_4-5X4-7'| '4.7UH/4A'                     | 'DISCRETE' | 'IND SMD 4.7UH +-20% 4A(PCMB053T-4R7MS)'        | 'CHIP'         | ''          | ''   | '20180823'  
 '4.7UH/4A'                     | 'SMLF'     | 'EMPTY'  | 'CV-4740MZ03'(!)           = ''              | ''                 | 'CV-4740MZ03'              |'L_CMME053T_4-5X4-7'| 'NA'                           | 'IO'       | 'IND SMD 4.7UH +-20% 4A(PCMB053T-4R7MS)'        | 'CHIP'         | ''          | ''   | '20180823'  
 '0.68UH/8.5A'                  | 'SMLF'     | 'IND'    | 'CV+6885MZ04'(!)           = ''              | ''                 | 'CV+6885MZ04'              |'L_CMME053T_4-5X4-7'| '0.68UH/8.5A'                  | 'DISCRETE' | 'INDSMD 0.68UH +-20% 8.5A(PCMB053T-R68MS)'      | 'CHIP'         | ''          | ''   | '20180823'  
 '0.68UH/8.5A'                  | 'SMLF'     | 'EMPTY'  | 'CV+6885MZ04'(!)           = ''              | ''                 | 'CV+6885MZ04'              |'L_CMME053T_4-5X4-7'| 'NA'                           | 'IO'       | 'INDSMD 0.68UH +-20% 8.5A(PCMB053T-R68MS)'      | 'CHIP'         | ''          | ''   | '20180823'  
 '0.15UH/115A'                  | 'SMLF'     | 'IND'    | 'CV+15^0KZ17'(!)           = ''              | ''                 | 'CV+15^0KZ17'              |'L_HCUVE117512D'| '0.15UH/115A'                  | 'DISCRETE' | 'IND SMD 0.15UH 10% 115A(MSI-110812V-R15K'      | 'CHIP'         | ''          | ''   | '20180903'  
 '0.15UH/115A'                  | 'SMLF'     | 'EMPTY'  | 'CV+15^0KZ17'(!)           = ''              | ''                 | 'CV+15^0KZ17'              |'L_HCUVE117512D'| 'NA'                           | 'IO'       | 'IND SMD 0.15UH 10% 115A(MSI-110812V-R15K'      | 'CHIP'         | ''          | ''   | '20180903'  
 '150NH/119A'                   | 'SMLF'     | 'IND'    | 'CVA15^0KZ00'(!)           = ''              | ''                 | 'CVA15^0KZ00'              |'L_HCUVE117512D'| '150NH/119A'                   | 'DISCRETE' | 'IND SMD 150NH 10% 119A(HCUVE117512-151)'       | 'CHIP'         | ''          | ''   | '20180906'  
 '150NH/119A'                   | 'SMLF'     | 'EMPTY'  | 'CVA15^0KZ00'(!)           = ''              | ''                 | 'CVA15^0KZ00'              |'L_HCUVE117512D'| 'NA'                           | 'IO'       | 'IND SMD 150NH 10% 119A(HCUVE117512-151)'       | 'CHIP'         | ''          | ''   | '20180906'  
 '150NH/76A'                    | 'SMLF'     | 'IND'    | 'CV+15^0KZ19'(!)           = ''              | ''                 | 'CV+15^0KZ19'              |'L_FP1007R3_10-2X7-8'| '150NH/76A'                    | 'DISCRETE' | 'IND SMD 150NH 10% 76A(FP1007R3-R15-R)'         | 'CHIP'         | ''          | ''   | '20181002'  
 '150NH/76A'                    | 'SMLF'     | 'EMPTY'  | 'CV+15^0KZ19'(!)           = ''              | ''                 | 'CV+15^0KZ19'              |'L_FP1007R3_10-2X7-8'| 'NA'                           | 'IO'       | 'IND SMD 150NH 10% 76A(FP1007R3-R15-R)'         | 'CHIP'         | ''          | ''   | '20181002'  
 '2.2UH/5.5A'                   | 'SMLF'     | 'IND'    | 'CV-2255MZ02'(!)           = ''              | ''                 | 'CV-2255MZ02'              |'L_CMME053T_4-5X4-7'| '2.2UH/5.5A'                   | 'DISCRETE' | 'IND SMD 2.2UH +-20% 5.5A(PCMB053T-2R2MS)'      | 'CHIP'         | ''          | ''   | '20181005'  
 '2.2UH/5.5A'                   | 'SMLF'     | 'EMPTY'  | 'CV-2255MZ02'(!)           = ''              | ''                 | 'CV-2255MZ02'              |'L_CMME053T_4-5X4-7'| 'NA'                           | 'IO'       | 'IND SMD 2.2UH +-20% 5.5A(PCMB053T-2R2MS)'      | 'CHIP'         | ''          | ''   | '20181005'  
 '3.3U/5A'                      | 'SMLF'     | 'IND'    | 'CV-3350MZ11'(!)           = ''              | ''                 | 'CV-3350MZ11'              |'L_CMME053T_4-5X4-7'| '3.3U/5A'                      | 'DISCRETE' | 'IND SMD 3.3U +-20% 5A(PCMB053T-3R3MS)'         | 'CHIP'         | ''          | ''   | '20181005'  
 '3.3U/5A'                      | 'SMLF'     | 'EMPTY'  | 'CV-3350MZ11'(!)           = ''              | ''                 | 'CV-3350MZ11'              |'L_CMME053T_4-5X4-7'| 'NA'                           | 'IO'       | 'IND SMD 3.3U +-20% 5A(PCMB053T-3R3MS)'         | 'CHIP'         | ''          | ''   | '20181005'  
 '10UH/3.7A'                    | 'SMLF'     | 'IND'    | 'CV01037MZ00'(!)           = ''              | ''                 | 'CV01037MZ00'              |'L_CMME053T_4-5X4-7'| '10UH/3.7A'                    | 'DISCRETE' | 'IND SMD 10UH 20% 3.7A(CMLE053T-100MS)'         | 'CHIP'         | ''          | ''   | '20181005'  
 '10UH/3.7A'                    | 'SMLF'     | 'EMPTY'  | 'CV01037MZ00'(!)           = ''              | ''                 | 'CV01037MZ00'              |'L_CMME053T_4-5X4-7'| 'NA'                           | 'IO'       | 'IND SMD 10UH 20% 3.7A(CMLE053T-100MS)'         | 'CHIP'         | ''          | ''   | '20181005'  
 '6.8UH/4.5A'                   | 'SMLF'     | 'IND'    | 'CV-6845MZ00'(!)           = ''              | ''                 | 'CV-6845MZ00'              |'L_MMD-06CZ'| '6.8UH/4.5A'                   | 'DISCRETE' | 'IND SMD 6.8UH 20% 4.5A MMD-06CZ-6R8M-V1Q'      | 'CHIP'         | ''          | ''   | '20181011'  
 '6.8UH/4.5A'                   | 'SMLF'     | 'EMPTY'  | 'CV-6845MZ00'(!)           = ''              | ''                 | 'CV-6845MZ00'              |'L_MMD-06CZ'| 'NA'                           | 'IO'       | 'IND SMD 6.8UH 20% 4.5A MMD-06CZ-6R8M-V1Q'      | 'CHIP'         | ''          | ''   | '20181011'  
 '50NH/86A'                     | 'SMLF'     | 'IND'    | 'CVA50^0MZ07'(!)           = ''              | ''                 | 'CVA50^0MZ07'              |'L_HCBS6170_6-1X6'| '50NH/86A'                     | 'DISCRETE' | 'IND SMD 50NH 20% 86A(HCBS6170-500)'            | 'CHIP'         | ''          | ''   | '20181015'  
 '50NH/86A'                     | 'SMLF'     | 'EMPTY'  | 'CVA50^0MZ07'(!)           = ''              | ''                 | 'CVA50^0MZ07'              |'L_HCBS6170_6-1X6'| 'NA'                           | 'IO'       | 'IND SMD 50NH 20% 86A(HCBS6170-500)'            | 'CHIP'         | ''          | ''   | '20181015'  
 '130NH/99A'                    | 'SMLF'     | 'IND'    | 'CV+13^0KZ04'(!)           = ''              | ''                 | 'CV+13^0KZ04'              |'L_HCUVE768012-171_7-6X8-1'| '130NH/99A'                    | 'DISCRETE' | 'IND SMD 130NH 10% 99A(HCUVE768012-131)'        | 'CHIP'         | ''          | ''   | '20181015'  
 '130NH/99A'                    | 'SMLF'     | 'EMPTY'  | 'CV+13^0KZ04'(!)           = ''              | ''                 | 'CV+13^0KZ04'              |'L_HCUVE768012-171_7-6X8-1'| 'NA'                           | 'IO'       | 'IND SMD 130NH 10% 99A(HCUVE768012-131)'        | 'CHIP'         | ''          | ''   | '20181015'  
 '130NH/95A'                    | 'SMLF'     | 'IND'    | 'CV+13^0KZ05'(!)           = 'End of Design' | 'Comp-Approve'     | 'CV+13^0KZ05'              |'L_HCUVE768012-171_7-6X8-1'| '130NH/95A'                    | 'DISCRETE' | 'IND SMD 130NH 10% 95A(HCUVE768012D-131)'       | 'CHIP'         | ''          | ''   | '20181015'  
 '130NH/95A'                    | 'SMLF'     | 'EMPTY'  | 'CV+13^0KZ05'(!)           = 'End of Design' | 'Comp-Approve'     | 'CV+13^0KZ05'              |'L_HCUVE768012-171_7-6X8-1'| 'NA'                           | 'IO'       | 'IND SMD 130NH 10% 95A(HCUVE768012D-131)'       | 'CHIP'         | ''          | ''   | '20181015'  
 '1.5UH/26A'                    | 'SMLF'     | 'IND'    | 'CV-15R0MZ00'(!)           = ''              | ''                 | 'CV-15R0MZ00'              |'L_PCMS136E_13-45X12-6'| '1.5UH/26A'                    | 'DISCRETE' | 'IND SMD 1.5UH +-20% 26A PCMS136E-1R5MF'        | 'CHIP'         | ''          | ''   | '20181025'  
 '1.5UH/26A'                    | 'SMLF'     | 'EMPTY'  | 'CV-15R0MZ00'(!)           = ''              | ''                 | 'CV-15R0MZ00'              |'L_PCMS136E_13-45X12-6'| 'NA'                           | 'IO'       | 'IND SMD 1.5UH +-20% 26A PCMS136E-1R5MF'        | 'CHIP'         | ''          | ''   | '20181025'  
 'FBMH2012HM331-T/1.8A'         | 'SMLF'     | 'IND'    | 'CX000331000'(!)           = 'End of Design' | 'Comp-Approve'     | 'CX000331000'              |'L0805'| 'FBMH2012HM331-T/1.8A'         | 'DISCRETE' | 'FILTER CHIP FBMH2012HM331 330,1.8A'            | 'CHIP'         | ''          | ''   | '20181026'  
 'FBMH2012HM331-T/1.8A'         | 'SMLF'     | 'EMPTY'  | 'CX000331000'(!)           = 'End of Design' | 'Comp-Approve'     | 'CX000331000'              |'L0805'| 'NA'                           | 'IO'       | 'FILTER CHIP FBMH2012HM331 330,1.8A'            | 'CHIP'         | ''          | ''   | '20181026'  
 '56NH/94A'                     | 'SMLF'     | 'IND'    | 'CVA56^0KZ00'(!)           = ''              | ''                 | 'CVA56^0KZ00'              |'L_TPI078060L056N_7X8'| '56NH/94A'                     | 'DISCRETE' | 'IND SMD 56NH 10% 94A(TPI078060L056N)'          | 'CHIP'         | ''          | ''   | '20181101'  
 '56NH/94A'                     | 'SMLF'     | 'EMPTY'  | 'CVA56^0KZ00'(!)           = ''              | ''                 | 'CVA56^0KZ00'              |'L_TPI078060L056N_7X8'| 'NA'                           | 'IO'       | 'IND SMD 56NH 10% 94A(TPI078060L056N)'          | 'CHIP'         | ''          | ''   | '20181101'  
 'BLM18EG221SN1D/2A'            | 'SMLF'     | 'IND'    | 'CX8EG221011'(!)           = 'End of Design' | 'Comp-Approve'     | 'CX8EG221011'              |'L0603'| 'BLM18EG221SN1D/2A'            | 'DISCRETE' | 'EMI FILTER BLM18EG221SN1D(220,2A)'             | 'CHIP'         | ''          | ''   | '20111228'  
 'BLM18EG221SN1D/2A'            | 'SMLF'     | 'EMPTY'  | 'CX8EG221011'(!)           = 'End of Design' | 'Comp-Approve'     | 'CX8EG221011'              |'L0603'| 'NA'                           | 'IO'       | 'EMI FILTER BLM18EG221SN1D(220,2A)'             | 'CHIP'         | ''          | ''   | '20111228'  
 'GMLB-160808-0600L-N8A/0.5A'   | 'SMLF'     | 'IND'    | 'CX080600003'(!)           = ''              | ''                 | 'CX080600003'              |'L0603'| 'GMLB-160808-0600L-N8A/0.5A'   | 'DISCRETE' | 'EMI FILT GMLB-160808-0600L-N8A(600,0.5A)'      | 'CHIP'         | ''          | ''   | '20181218'  
 'GMLB-160808-0600L-N8A/0.5A'   | 'SMLF'     | 'EMPTY'  | 'CX080600003'(!)           = ''              | ''                 | 'CX080600003'              |'L0603'| 'NA'                           | 'IO'       | 'EMI FILT GMLB-160808-0600L-N8A(600,0.5A)'      | 'CHIP'         | ''          | ''   | '20181218'  
 '0.15UH/35A'                   | 'SMLF'     | 'IND'    | 'CV+15^0MZ37'(!)           = ''              | ''                 | 'CV+15^0MZ37'              |'L_MMD-10BZNR15M-M1Q_11-5X10'| '0.15UH/35A'                   | 'DISCRETE' | 'IND SMD 0.15U 20% 35A(MMD-10BZNR15M-M1Q)'      | 'CHIP'         | ''          | ''   | '20181219'  
 '0.15UH/35A'                   | 'SMLF'     | 'EMPTY'  | 'CV+15^0MZ37'(!)           = ''              | ''                 | 'CV+15^0MZ37'              |'L_MMD-10BZNR15M-M1Q_11-5X10'| 'NA'                           | 'IO'       | 'IND SMD 0.15U 20% 35A(MMD-10BZNR15M-M1Q)'      | 'CHIP'         | ''          | ''   | '20181219'  
 '0.15U/27A'                    | 'SMLF'     | 'IND'    | 'CV+15S0MZ02'(!)           = ''              | ''                 | 'CV+15S0MZ02'              |'L_MMD-05BZ_5-49X5-18'| '0.15U/27A'                    | 'DISCRETE' | 'IND SMD 0.15U 20% 27A(MMD-05BZ-R15M-R1Q)'      | 'CHIP'         | ''          | ''   | '20190103'  
 '0.15U/27A'                    | 'SMLF'     | 'EMPTY'  | 'CV+15S0MZ02'(!)           = ''              | ''                 | 'CV+15S0MZ02'              |'L_MMD-05BZ_5-49X5-18'| 'NA'                           | 'IO'       | 'IND SMD 0.15U 20% 27A(MMD-05BZ-R15M-R1Q)'      | 'CHIP'         | ''          | ''   | '20190103'  
 'HCB1608KF-601T20/2A'          | 'SMLF'     | 'IND'    | 'CX601T20001'(!)           = ''              | ''                 | 'CX601T20001'              |'L0603'| 'HCB1608KF-601T20/2A'          | 'DISCRETE' | 'EMI FILTER CHIP HCB1608KF-601T20(600,2A)'      | 'CHIP'         | ''          | ''   | '20190110'  
 'HCB1608KF-601T20/2A'          | 'SMLF'     | 'EMPTY'  | 'CX601T20001'(!)           = ''              | ''                 | 'CX601T20001'              |'L0603'| 'NA'                           | 'IO'       | 'EMI FILTER CHIP HCB1608KF-601T20(600,2A)'      | 'CHIP'         | ''          | ''   | '20190110'  
 '1UH/4.2A'                     | 'SMLF'     | 'IND'    | 'CV-1042MZ11'(!)           = ''              | ''                 | 'CV-1042MZ11'              |'L_MLV-YT12N_2-5X2'| '1UH/4.2A'                     | 'DISCRETE' | 'IND SMD 1UH 20% 4.2A(MLV-YT12N1R0M-C2Q)'       | 'CHIP'         | ''          | ''   | '20190125'  
 '1UH/4.2A'                     | 'SMLF'     | 'EMPTY'  | 'CV-1042MZ11'(!)           = ''              | ''                 | 'CV-1042MZ11'              |'L_MLV-YT12N_2-5X2'| 'NA'                           | 'IO'       | 'IND SMD 1UH 20% 4.2A(MLV-YT12N1R0M-C2Q)'       | 'CHIP'         | ''          | ''   | '20190125'  
 'BLM15PD800SN1D/1000A'         | 'SMLF'     | 'IND'    | 'CX5PD800000'(!)           = ''              | ''                 | 'CX5PD800000'              |'L0402'| 'BLM15PD800SN1D'               | 'DISCRETE' | 'EMI FILTER BLM15PD800SN1D(80,1000MA)'          | 'CHIP'         | ''          | ''   | '20190130'  
 'BLM15PD800SN1D/1000A'         | 'SMLF'     | 'EMPTY'  | 'CX5PD800000'(!)           = ''              | ''                 | 'CX5PD800000'              |'L0402'| 'NA'                           | 'IO'       | 'EMI FILTER BLM15PD800SN1D(80,1000MA)'          | 'CHIP'         | ''          | ''   | '20190130'  
 'BK1005HS800-T/0.7A'           | 'SMLF'     | 'IND'    | 'CX5HS800000'(!)           = 'End of Design' | 'Comp-Release Qty' | 'CX5HS800000'              |'L0402'| 'BK1005HS800-T'                | 'DISCRETE' | 'EMI FILTER BK1005HS800-T(80,0.7A)'             | 'CHIP'         | ''          | ''   | '20190130'  
 'BK1005HS800-T/0.7A'           | 'SMLF'     | 'EMPTY'  | 'CX5HS800000'(!)           = 'End of Design' | 'Comp-Release Qty' | 'CX5HS800000'              |'L0402'| 'NA'                           | 'IO'       | 'EMI FILTER BK1005HS800-T(80,0.7A)'             | 'CHIP'         | ''          | ''   | '20190130'  
 '0.4UH/25A'                    | 'SMLF'     | 'IND'    | 'CV+04Q0KZ00'(!)           = ''              | ''                 | 'CV+04Q0KZ00'              |'L_FP1107R2-R40-R'| '0.4UH/25A'                    | 'DISCRETE' | 'IND SMD 0.4UH 10% 25A(FP1107R2-R40-R)'         | 'CHIP'         | ''          | ''   | '20190215'  
 '0.4UH/25A'                    | 'SMLF'     | 'EMPTY'  | 'CV+04Q0KZ00'(!)           = ''              | ''                 | 'CV+04Q0KZ00'              |'L_FP1107R2-R40-R'| 'NA'                           | 'IO'       | 'IND SMD 0.4UH 10% 25A(FP1107R2-R40-R)'         | 'CHIP'         | ''          | ''   | '20190215'  
 'HCB1608KF-600T30/3A'          | 'SMLF'     | 'IND'    | 'CX600T30000'(!)           = ''              | ''                 | 'CX600T30000'              |'L0603'| 'HCB1608KF-600T30/3A'          | 'DISCRETE' | 'EMI FILTER HCB1608KF-600T30(60,3A)'            | 'CHIP'         | ''          | ''   | '20190220'  
 'HCB1608KF-600T30/3A'          | 'SMLF'     | 'EMPTY'  | 'CX600T30000'(!)           = ''              | ''                 | 'CX600T30000'              |'L0603'| 'NA'                           | 'IO'       | 'EMI FILTER HCB1608KF-600T30(60,3A)'            | 'CHIP'         | ''          | ''   | '20190220'  
 '220NH/61A'                    | 'SMLF'     | 'IND'    | 'CV+22^0KZ19'(!)           = 'End of Design' | 'Comp-Approve'     | 'CV+22^0KZ19'              |'L_HCUVE966412D-221'| '220NH/61A'                    | 'DISCRETE' | 'IND SMD 220NH 10% 61A(HCUVE966412D-221)'       | 'CHIP'         | ''          | ''   | '20160727'  
 '220NH/61A'                    | 'SMLF'     | 'EMPTY'  | 'CV+22^0KZ19'(!)           = 'End of Design' | 'Comp-Approve'     | 'CV+22^0KZ19'              |'L_HCUVE966412D-221'| 'NA'                           | 'IO'       | 'IND SMD 220NH 10% 61A(HCUVE966412D-221)'       | 'CHIP'         | ''          | ''   | '20160727'  
 '82NH/10A'                     | 'SMLF'     | 'IND'    | 'CVA82A0MZ00'(!)           = ''              | ''                 | 'CVA82A0MZ00'              |'L_MSI-400403_4-5X4-5'| '82NH/10A'                     | 'DISCRETE' | 'IND SMD 82NH 20% 10A(MSI-400403-82NM'          | 'CHIP'         | ''          | ''   | '20190320'  
 '82NH/10A'                     | 'SMLF'     | 'EMPTY'  | 'CVA82A0MZ00'(!)           = ''              | ''                 | 'CVA82A0MZ00'              |'L_MSI-400403_4-5X4-5'| 'NA'                           | 'IO'       | 'IND SMD 82NH 20% 10A(MSI-400403-82NM'          | 'CHIP'         | ''          | ''   | '20190320'  
 '0.1UH/20A'                    | 'SMLF'     | 'IND'    | 'CV+10K0MZ00'(!)           = ''              | ''                 | 'CV+10K0MZ00'              |'L_MSI-600603_6-5X6'| '0.1UH/20A'                    | 'DISCRETE' | 'IND SMD 0.1UH 20% 20A(MSI-600603-R10M'         | 'CHIP'         | ''          | ''   | '20190320'  
 '0.1UH/20A'                    | 'SMLF'     | 'EMPTY'  | 'CV+10K0MZ00'(!)           = ''              | ''                 | 'CV+10K0MZ00'              |'L_MSI-600603_6-5X6'| 'NA'                           | 'IO'       | 'IND SMD 0.1UH 20% 20A(MSI-600603-R10M'         | 'CHIP'         | ''          | ''   | '20190320'  
 '1UH/9.2A'                     | 'SMLF'     | 'IND'    | 'CV-1092MZ01'(!)           = ''              | ''                 | 'CV-1092MZ01'              |'L_MMD-05CZ-3R3M-M2Q'| '1UH/9.2A'                     | 'DISCRETE' | 'IND SMD 1UH 20% 9.2A(MMD-05CZ-1R0M-V7Q)'       | 'CHIP'         | ''          | ''   | '20190329'  
 '1UH/9.2A'                     | 'SMLF'     | 'EMPTY'  | 'CV-1092MZ01'(!)           = ''              | ''                 | 'CV-1092MZ01'              |'L_MMD-05CZ-3R3M-M2Q'| 'NA'                           | 'IO'       | 'IND SMD 1UH 20% 9.2A(MMD-05CZ-1R0M-V7Q)'       | 'CHIP'         | ''          | ''   | '20190329'  
 '47NH/90A'                     | 'SMLF'     | 'IND'    | 'CVA47^0KZ00'(!)           = ''              | ''                 | 'CVA47^0KZ00'              |'L_TPI078060L056N_7X8'| '47NH/90A'                     | 'DISCRETE' | 'IND SMD 47NH 10% 90A(TPI078060L047N)'          | 'CHIP'         | ''          | ''   | '20190410'  
 '47NH/90A'                     | 'SMLF'     | 'EMPTY'  | 'CVA47^0KZ00'(!)           = ''              | ''                 | 'CVA47^0KZ00'              |'L_TPI078060L056N_7X8'| 'NA'                           | 'IO'       | 'IND SMD 47NH 10% 90A(TPI078060L047N)'          | 'CHIP'         | ''          | ''   | '20190410'  
 '900NH/47A'                    | 'SMLF'     | 'IND'    | 'CV+90^0KZ00'(!)           = ''              | ''                 | 'CV+90^0KZ00'              |'L_HCUVD1115_11X8XA'| '900NH/47A'                    | 'DISCRETE' | 'IND SMD 900NH 10% 47A(HCUVD1115-901QL)'        | 'CHIP'         | ''          | ''   | '20190424'  
 '900NH/47A'                    | 'SMLF'     | 'EMPTY'  | 'CV+90^0KZ00'(!)           = ''              | ''                 | 'CV+90^0KZ00'              |'L_HCUVD1115_11X8XA'| 'NA'                           | 'IO'       | 'IND SMD 900NH 10% 47A(HCUVD1115-901QL)'        | 'CHIP'         | ''          | ''   | '20190424'  
 'MHC3216S121WBE/6A'            | 'SMLF'     | 'IND'    | 'CX16S121001'(!)           = ''              | ''                 | 'CX16S121001'              |'L1206XC'| 'MHC3216S121WBE/6A'            | 'DISCRETE' | 'EMI FILTER BEAD MHC3216S121WBE(120,6A)'        | 'CHIP'         | ''          | ''   | '20190429'  
 'MHC3216S121WBE/6A'            | 'SMLF'     | 'EMPTY'  | 'CX16S121001'(!)           = ''              | ''                 | 'CX16S121001'              |'L1206XC'| 'NA'                           | 'IO'       | 'EMI FILTER BEAD MHC3216S121WBE(120,6A)'        | 'CHIP'         | ''          | ''   | '20190429'  
 '50N/86A'                      | 'SMLF'     | 'IND'    | 'CVA50^0MZ08'(!)           = ''              | ''                 | 'CVA50^0MZ08'              |'L_HCBS6170_6-1X6'| '50N/86A'                      | 'DISCRETE' | 'IND SMD 50N 20% 86A(MSI-600607-50NM-E-QU'      | 'CHIP'         | ''          | ''   | '20190426'  
 '50N/86A'                      | 'SMLF'     | 'EMPTY'  | 'CVA50^0MZ08'(!)           = ''              | ''                 | 'CVA50^0MZ08'              |'L_HCBS6170_6-1X6'| 'NA'                           | 'IO'       | 'IND SMD 50N 20% 86A(MSI-600607-50NM-E-QU'      | 'CHIP'         | ''          | ''   | '20190426'  
 '100NH/95A'                    | 'SMLF'     | 'IND'    | 'CV+10^0KZ04'(!)           = ''              | ''                 | 'CV+10^0KZ04'              |'L_AH3740A-100K_9-5X6-4'| '100NH/95A'                    | 'DISCRETE' | 'IND SMD 100NH 10% 95A(AH3740A-100K)'           | 'CHIP'         | ''          | ''   | '20190521'  
 '100NH/95A'                    | 'SMLF'     | 'EMPTY'  | 'CV+10^0KZ04'(!)           = ''              | ''                 | 'CV+10^0KZ04'              |'L_AH3740A-100K_9-5X6-4'| 'NA'                           | 'IO'       | 'IND SMD 100NH 10% 95A(AH3740A-100K)'           | 'CHIP'         | ''          | ''   | '20190521'  
 '10UH/200MA'                   | 'SMLF'     | 'IND'    | 'CV01002MN10'(!)           = ''              | ''                 | 'CV01002MN10'              |'L0805_H62'| '10UH/200MA'                   | 'DISCRETE' | 'IND CHIP 10UH +-20% 200MA(MLZ2012M100HT)'      | 'CHIP'         | ''          | ''   | '20190603'  
 '10UH/200MA'                   | 'SMLF'     | 'EMPTY'  | 'CV01002MN10'(!)           = ''              | ''                 | 'CV01002MN10'              |'L0805_H62'| 'NA'                           | 'IO'       | 'IND CHIP 10UH +-20% 200MA(MLZ2012M100HT)'      | 'CHIP'         | ''          | ''   | '20190603'  
 '4.7UH/48A'                    | 'SMLF'     | 'IND'    | 'CV-47^0KZ02'(!)           = ''              | ''                 | 'CV-47^0KZ02'              |'L_SER2814H_27-9X19-3'| '4.7UH/48A'                    | 'DISCRETE' | 'IND SMD 4.7UH 10% 48A(SER2814H-472KL)'         | 'CHIP'         | ''          | ''   | '20190604'  
 '4.7UH/48A'                    | 'SMLF'     | 'EMPTY'  | 'CV-47^0KZ02'(!)           = ''              | ''                 | 'CV-47^0KZ02'              |'L_SER2814H_27-9X19-3'| 'NA'                           | 'IO'       | 'IND SMD 4.7UH 10% 48A(SER2814H-472KL)'         | 'CHIP'         | ''          | ''   | '20190604'  
 '55N/63A'                      | 'SMLF'     | 'IND'    | 'CVA55^0TZ00'(!)           = ''              | ''                 | 'CVA55^0TZ00'              |'L_SL2218A_5-35X5-7'| '55N/63A'                      | 'DISCRETE' | 'IND SMD 55N 15% 63A(SL2218A-R055LHF)'          | 'CHIP'         | ''          | ''   | '20190606'  
 '55N/63A'                      | 'SMLF'     | 'EMPTY'  | 'CVA55^0TZ00'(!)           = ''              | ''                 | 'CVA55^0TZ00'              |'L_SL2218A_5-35X5-7'| 'NA'                           | 'IO'       | 'IND SMD 55N 15% 63A(SL2218A-R055LHF)'          | 'CHIP'         | ''          | ''   | '20190606'  
 '0.82UH/31A'                   | 'SMLF'     | 'IND'    | 'CV+82W0MZ01'(!)           = ''              | ''                 | 'CV+82W0MZ01'              |'L_PCMC135T'| '0.82UH/31A'                   | 'DISCRETE' | 'IND SMD 0.82UH +-20%31A(PCMC135T-R82)'         | 'CHIP'         | ''          | ''   | '20190709'  
 '0.82UH/31A'                   | 'SMLF'     | 'EMPTY'  | 'CV+82W0MZ01'(!)           = ''              | ''                 | 'CV+82W0MZ01'              |'L_PCMC135T'| 'NA'                           | 'IO'       | 'IND SMD 0.82UH +-20%31A(PCMC135T-R82)'         | 'CHIP'         | ''          | ''   | '20190709'  
 '0.33UH/13.5A'                 | 'SMLF'     | 'IND'    | 'CV+33D5MZ00'(!)           = ''              | ''                 | 'CV+33D5MZ00'              |'L_MMD-06AEE_6-86X6-47'| '0.33UH/13.5A'                 | 'DISCRETE' | 'IND SMD 0.33UH20%13.5A,(CMME061E-R33MS)'       | 'CHIP'         | ''          | ''   | '20190716'  
 '0.33UH/13.5A'                 | 'SMLF'     | 'EMPTY'  | 'CV+33D5MZ00'(!)           = ''              | ''                 | 'CV+33D5MZ00'              |'L_MMD-06AEE_6-86X6-47'| 'NA'                           | 'IO'       | 'IND SMD 0.33UH20%13.5A,(CMME061E-R33MS)'       | 'CHIP'         | ''          | ''   | '20190716'  
 '1.0UH/13.5A'                  | 'SMLF'     | 'IND'    | 'CV-10D5MZ00'(!)           = ''              | ''                 | 'CV-10D5MZ00'              |'L_VCMT063T-2R2MN5'| '1.0UH/13.5A'                  | 'DISCRETE' | 'IND SMD 1.0U +-20% 13.5A(PCME063T-1R0MS)'      | 'CHIP'         | ''          | ''   | '20190726'  
 '1.0UH/13.5A'                  | 'SMLF'     | 'EMPTY'  | 'CV-10D5MZ00'(!)           = ''              | ''                 | 'CV-10D5MZ00'              |'L_VCMT063T-2R2MN5'| 'NA'                           | 'IO'       | 'IND SMD 1.0U +-20% 13.5A(PCME063T-1R0MS)'      | 'CHIP'         | ''          | ''   | '20190726'  
 '4UH/40A'                      | 'SMLF'     | 'IND'    | 'CV-40^0TZ00'(!)           = 'Non-Preferred' | 'End of Life'      | 'CV-40^0TZ00'              |'LC_61126_EOL'| '4UH/40A'                      | 'DISCRETE' | 'IND SMD 4UH +15/-30% 40A(61126)'               | 'CHIP'         | ''          | ''   | '20190724'  
 '4UH/40A'                      | 'SMLF'     | 'EMPTY'  | 'CV-40^0TZ00'(!)           = 'Non-Preferred' | 'End of Life'      | 'CV-40^0TZ00'              |'LC_61126_EOL'| 'NA'                           | 'IO'       | 'IND SMD 4UH +15/-30% 40A(61126)'               | 'CHIP'         | ''          | ''   | '20190724'  
 '220NH/61A'                    | 'SMLF'     | 'IND'    | 'CV122^0KZ01'(!)           = 'End of Design' | 'Comp-Release Qty' | 'CV122^0KZ01'              |'L_HCUVE966412D-221'| '220NH/61A'                    | 'DISCRETE' | 'IND SMD 220NH 10% 61A(HCUVE9612D-221QL)'       | 'CHIP'         | ''          | ''   | '20190807'  
 '220NH/61A'                    | 'SMLF'     | 'EMPTY'  | 'CV122^0KZ01'(!)           = 'End of Design' | 'Comp-Release Qty' | 'CV122^0KZ01'              |'L_HCUVE966412D-221'| 'NA'                           | 'IO'       | 'IND SMD 220NH 10% 61A(HCUVE9612D-221QL)'       | 'CHIP'         | ''          | ''   | '20190807'  
 '1UH/17.5A'                    | 'SMLF'     | 'IND'    | 'CV-1018MZ09'(!)           = ''              | ''                 | 'CV-1018MZ09'              |'L_CMML065T_6-6X6-6'| '1UH/17.5A'                    | 'DISCRETE' | 'IND SMD 1UH20%17.5A(CMML065T-1R0ME3R607)'      | 'CHIP'         | ''          | ''   | '20190808'  
 '1UH/17.5A'                    | 'SMLF'     | 'EMPTY'  | 'CV-1018MZ09'(!)           = ''              | ''                 | 'CV-1018MZ09'              |'L_CMML065T_6-6X6-6'| 'NA'                           | 'IO'       | 'IND SMD 1UH20%17.5A(CMML065T-1R0ME3R607)'      | 'CHIP'         | ''          | ''   | '20190808'  
 '1UH/14.5A'                    | 'SMLF'     | 'IND'    | 'CV-10E5MZ02'(!)           = ''              | ''                 | 'CV-10E5MZ02'              |'L_VCMT063T-2R2MN5_H158'| '1UH/14.5A'                    | 'DISCRETE' | 'IND SMD 1UH 20%14.5A,CMME064T-1R0MS'           | 'CHIP'         | ''          | ''   | '20190814'  
 '1UH/14.5A'                    | 'SMLF'     | 'EMPTY'  | 'CV-10E5MZ02'(!)           = ''              | ''                 | 'CV-10E5MZ02'              |'L_VCMT063T-2R2MN5_H158'| 'NA'                           | 'IO'       | 'IND SMD 1UH 20%14.5A,CMME064T-1R0MS'           | 'CHIP'         | ''          | ''   | '20190814'  
 '1UH/7A'                       | 'SMLF'     | 'IND'    | 'CV-1070MZ12'(!)           = ''              | ''                 | 'CV-1070MZ12'              |'L_MMD-05CZ-2R2M-X2Q'| '1UH/7A'                       | 'DISCRETE' | 'IND SMD 1UH+-20%7A(MMD-05CZ-1R0M-X7Q)'         | 'CHIP'         | ''          | ''   | '20190819'  
 '1UH/7A'                       | 'SMLF'     | 'EMPTY'  | 'CV-1070MZ12'(!)           = ''              | ''                 | 'CV-1070MZ12'              |'L_MMD-05CZ-2R2M-X2Q'| 'NA'                           | 'IO'       | 'IND SMD 1UH+-20%7A(MMD-05CZ-1R0M-X7Q)'         | 'CHIP'         | ''          | ''   | '20190819'  
 '4UH/45A'                      | 'SMLF'     | 'IND'    | 'CV-40^0TZ01'(!)           = 'Non-Preferred' | 'End of Life'      | 'CV-40^0TZ01'              |'LC_61126_EOL'| '4UH/45A'                      | 'DISCRETE' | 'IND SMD 4UH +15/-30% 45A(61126R02)'            | 'CHIP'         | ''          | ''   | '20190827'  
 '4UH/45A'                      | 'SMLF'     | 'EMPTY'  | 'CV-40^0TZ01'(!)           = 'Non-Preferred' | 'End of Life'      | 'CV-40^0TZ01'              |'LC_61126_EOL'| 'NA'                           | 'IO'       | 'IND SMD 4UH +15/-30% 45A(61126R02)'            | 'CHIP'         | ''          | ''   | '20190827'  
 'BLM31PG121SN1L/3A'            | 'SMLF'     | 'IND'    | 'CX1PG121006'(!)           = 'End of Design' | 'Comp-Approve'     | 'CX1PG121006'              |'L1206XD'| 'BLM31PG121SN1L/3A'            | 'DISCRETE' | 'EMI CHIP BLM31PG121SN1L(120,3A)'               | 'CHIP'         | ''          | ''   | '20190902'  
 'BLM31PG121SN1L/3A'            | 'SMLF'     | 'EMPTY'  | 'CX1PG121006'(!)           = 'End of Design' | 'Comp-Approve'     | 'CX1PG121006'              |'L1206XD'| 'NA'                           | 'IO'       | 'EMI CHIP BLM31PG121SN1L(120,3A)'               | 'CHIP'         | ''          | ''   | '20190902'  
 '1UH/16A'                      | 'SMLF'     | 'IND'    | 'CV-10G0MZ02'(!)           = ''              | ''                 | 'CV-10G0MZ02'              |'L_MMD-06DZ'| '1UH/16A'                      | 'DISCRETE' | 'IND SMD 1UH 20%16A,MMD-06DZE1R0M-M1Q'          | 'CHIP'         | ''          | ''   | '20190906'  
 '1UH/16A'                      | 'SMLF'     | 'EMPTY'  | 'CV-10G0MZ02'(!)           = ''              | ''                 | 'CV-10G0MZ02'              |'L_MMD-06DZ'| 'NA'                           | 'IO'       | 'IND SMD 1UH 20%16A,MMD-06DZE1R0M-M1Q'          | 'CHIP'         | ''          | ''   | '20190906'  
 '130NH/106A'                   | 'SMLF'     | 'IND'    | 'CV+13^0KZ08'(!)           = ''              | ''                 | 'CV+13^0KZ08'              |'L_HCME107512-131_10X7-5'| '130NH/106A'                   | 'DISCRETE' | 'IND SMD 130NH 10% 106A(HCME107512Q-131QL'      | 'CHIP'         | ''          | ''   | '20190909'  
 '130NH/106A'                   | 'SMLF'     | 'EMPTY'  | 'CV+13^0KZ08'(!)           = ''              | ''                 | 'CV+13^0KZ08'              |'L_HCME107512-131_10X7-5'| 'NA'                           | 'IO'       | 'IND SMD 130NH 10% 106A(HCME107512Q-131QL'      | 'CHIP'         | ''          | ''   | '20190909'  
 '130NH/95A'                    | 'SMLF'     | 'IND'    | 'CV+13^0KZ09'(!)           = ''              | ''                 | 'CV+13^0KZ09'              |'L_HCUVE768012-171_7-6X8-1'| '130NH/95A'                    | 'DISCRETE' | 'IND SMD 130NH 10% 95A(HCUVE768012Q-131QL'      | 'CHIP'         | ''          | ''   | '20190909'  
 '130NH/95A'                    | 'SMLF'     | 'EMPTY'  | 'CV+13^0KZ09'(!)           = ''              | ''                 | 'CV+13^0KZ09'              |'L_HCUVE768012-171_7-6X8-1'| 'NA'                           | 'IO'       | 'IND SMD 130NH 10% 95A(HCUVE768012Q-131QL'      | 'CHIP'         | ''          | ''   | '20190909'  
 '3.7UH/45A'                    | 'SMLF'     | 'IND'    | 'CV-37^0TZ00'(!)           = 'Non-Preferred' | 'End of Life'      | 'CV-37^0TZ00'              |'LC_61126_H504_EOL'| '3.7UH/45A'                    | 'DISCRETE' | 'IND SMD 3.7UH +15/-30% 45A(61126R03)'          | 'CHIP'         | ''          | ''   | '20190918'  
 '3.7UH/45A'                    | 'SMLF'     | 'EMPTY'  | 'CV-37^0TZ00'(!)           = 'Non-Preferred' | 'End of Life'      | 'CV-37^0TZ00'              |'LC_61126_H504_EOL'| 'NA'                           | 'IO'       | 'IND SMD 3.7UH +15/-30% 45A(61126R03)'          | 'CHIP'         | ''          | ''   | '20190918'  
 'BLM41PG471SN1L/2A'            | 'SMLF'     | 'IND'    | 'CX41PG47000'(!)           = ''              | ''                 | 'CX41PG47000'              |'L1806XA'| 'BLM41PG471SN1L/2A'            | 'DISCRETE' | 'EMI FILTER CHIP BLM41PG471SN1L(470,2A)'        | 'CHIP'         | ''          | ''   | '20191002'  
 'BLM41PG471SN1L/2A'            | 'SMLF'     | 'EMPTY'  | 'CX41PG47000'(!)           = ''              | ''                 | 'CX41PG47000'              |'L1806XA'| 'NA'                           | 'IO'       | 'EMI FILTER CHIP BLM41PG471SN1L(470,2A)'        | 'CHIP'         | ''          | ''   | '20191002'  
 '1UH/18A'                      | 'SMLF'     | 'IND'    | 'CV-10I0MZ14'(!)           = ''              | ''                 | 'CV-10I0MZ14'              |'L_VCMT063T-2R2MN5_H158'| '1UH/18A'                      | 'DISCRETE' | 'IND SMD 1UH 20% 18A(CMLE064T-1R0MS)'           | 'CHIP'         | ''          | ''   | '20191002'  
 '1UH/18A'                      | 'SMLF'     | 'EMPTY'  | 'CV-10I0MZ14'(!)           = ''              | ''                 | 'CV-10I0MZ14'              |'L_VCMT063T-2R2MN5_H158'| 'NA'                           | 'IO'       | 'IND SMD 1UH 20% 18A(CMLE064T-1R0MS)'           | 'CHIP'         | ''          | ''   | '20191002'  
 'MPZ1608S221ATD25/2.2A'        | 'SMLF'     | 'IND'    | 'CXS221AT000'(!)           = ''              | ''                 | 'CXS221AT000'              |'L0603'| 'MPZ1608S221ATD25/2.2A'        | 'DISCRETE' | 'EMI FILTER MPZ1608S221ATD25 (220,2.2A)'        | 'CHIP'         | ''          | ''   | '20191030'  
 'MPZ1608S221ATD25/2.2A'        | 'SMLF'     | 'EMPTY'  | 'CXS221AT000'(!)           = ''              | ''                 | 'CXS221AT000'              |'L0603'| 'NA'                           | 'IO'       | 'EMI FILTER MPZ1608S221ATD25 (220,2.2A)'        | 'CHIP'         | ''          | ''   | '20191030'  
 'HCB2012KF-331T30/3A'          | 'SMLF'     | 'IND'    | 'CX002012001'(!)           = ''              | ''                 | 'CX002012001'              |'L0805'| 'HCB2012KF-331T30/3A'          | 'DISCRETE' | 'EMI FILTER BEAD HCB2012KF-331T30(330,3A)'      | 'CHIP'         | ''          | ''   | '20191115'  
 'HCB2012KF-331T30/3A'          | 'SMLF'     | 'EMPTY'  | 'CX002012001'(!)           = ''              | ''                 | 'CX002012001'              |'L0805'| 'NA'                           | 'IO'       | 'EMI FILTER BEAD HCB2012KF-331T30(330,3A)'      | 'CHIP'         | ''          | ''   | '20191115'  
 'HCB2012VF-331T15/1.5A'        | 'SMLF'     | 'IND'    | 'CX331T15000'(!)           = ''              | ''                 | 'CX331T15000'              |'L0805'| 'HCB2012VF-331T15/1.5A'        | 'DISCRETE' | 'EMI FILTER HCB2012VF-331T15(330,1.5A)'         | 'CHIP'         | ''          | ''   | '20191121'  
 'HCB2012VF-331T15/1.5A'        | 'SMLF'     | 'EMPTY'  | 'CX331T15000'(!)           = ''              | ''                 | 'CX331T15000'              |'L0805'| 'NA'                           | 'IO'       | 'EMI FILTER HCB2012VF-331T15(330,1.5A)'         | 'CHIP'         | ''          | ''   | '20191121'  
 'HCB2012KF-220T60/6A'          | 'SMLF'     | 'IND'    | 'CX000220011'(!)           = ''              | ''                 | 'CX000220011'              |'L0805'| 'HCB2012KF-220T60/6A'          | 'DISCRETE' | 'EMI FILTER CHIP HCB2012KF220T60(22 6A)'        | 'CHIP'         | ''          | ''   | '20191128'  
 'HCB2012KF-220T60/6A'          | 'SMLF'     | 'EMPTY'  | 'CX000220011'(!)           = ''              | ''                 | 'CX000220011'              |'L0805'| 'NA'                           | 'IO'       | 'EMI FILTER CHIP HCB2012KF220T60(22 6A)'        | 'CHIP'         | ''          | ''   | '20191128'  
 '0.33UH/65A'                   | 'SMLF'     | 'IND'    | 'CV+33^0MZ03'(!)           = ''              | ''                 | 'CV+33^0MZ03'              |'L_MMD12FD'| '0.33UH/65A'                   | 'DISCRETE' | 'IND SMD 0.33UH 20% 65A(MMD-12FD-R33M-V1Q'      | 'CHIP'         | ''          | ''   | '20191204'  
 '0.33UH/65A'                   | 'SMLF'     | 'EMPTY'  | 'CV+33^0MZ03'(!)           = ''              | ''                 | 'CV+33^0MZ03'              |'L_MMD12FD'| 'NA'                           | 'IO'       | 'IND SMD 0.33UH 20% 65A(MMD-12FD-R33M-V1Q'      | 'CHIP'         | ''          | ''   | '20191204'  
 '0.36UH/25A'                   | 'SMLF'     | 'IND'    | 'CV+36Q0MZ00'(!)           = ''              | ''                 | 'CV+36Q0MZ00'              |'L_ETQP4LR22AFM'| '0.36UH/25A'                   | 'DISCRETE' | 'IND SMD 0.36U +-20%,25A (ETQP4LR36AFM)'        | 'CHIP'         | ''          | ''   | '20191205'  
 '0.36UH/25A'                   | 'SMLF'     | 'EMPTY'  | 'CV+36Q0MZ00'(!)           = ''              | ''                 | 'CV+36Q0MZ00'              |'L_ETQP4LR22AFM'| 'NA'                           | 'IO'       | 'IND SMD 0.36U +-20%,25A (ETQP4LR36AFM)'        | 'CHIP'         | ''          | ''   | '20191205'  
 '0.24UH/24A'                   | 'SMLF'     | 'IND'    | 'CV+24P0MZ00'(!)           = ''              | ''                 | 'CV+24P0MZ00'              |'L_ETQP4LR22AFM'| '0.24UH/24A'                   | 'DISCRETE' | 'IND SMD 0.24UH +-20% 24A(ETQP4LR24AFM)'        | 'CHIP'         | ''          | ''   | '20191209'  
 '0.24UH/24A'                   | 'SMLF'     | 'EMPTY'  | 'CV+24P0MZ00'(!)           = ''              | ''                 | 'CV+24P0MZ00'              |'L_ETQP4LR22AFM'| 'NA'                           | 'IO'       | 'IND SMD 0.24UH +-20% 24A(ETQP4LR24AFM)'        | 'CHIP'         | ''          | ''   | '20191209'  
 '0.42UH/20A'                   | 'SMLF'     | 'IND'    | 'CV+42K0MZ02'(!)           = ''              | ''                 | 'CV+42K0MZ02'              |'L_ETQP4LR22AFM'| '0.42UH/20A'                   | 'DISCRETE' | 'IND SMD 0.42U +-20%,20A (ETQP4LR42AFM)'        | 'CHIP'         | ''          | ''   | '20191209'  
 '0.42UH/20A'                   | 'SMLF'     | 'EMPTY'  | 'CV+42K0MZ02'(!)           = ''              | ''                 | 'CV+42K0MZ02'              |'L_ETQP4LR22AFM'| 'NA'                           | 'IO'       | 'IND SMD 0.42U +-20%,20A (ETQP4LR42AFM)'        | 'CHIP'         | ''          | ''   | '20191209'  
 '1UH/24A'                      | 'SMLF'     | 'IND'    | 'CV-10P0MZ04'(!)           = 'Non-Preferred' | 'End of Life'      | 'CV-10P0MZ04'              |'L_EM-10AM34VG1_7-9X7-1_EOL'| '1UH/24A'                      | 'DISCRETE' | 'IND SMD 1UH 20% 24A(EM-10AM34VG1)'             | 'CHIP'         | ''          | ''   | '20191209'  
 '1UH/24A'                      | 'SMLF'     | 'EMPTY'  | 'CV-10P0MZ04'(!)           = 'Non-Preferred' | 'End of Life'      | 'CV-10P0MZ04'              |'L_EM-10AM34VG1_7-9X7-1_EOL'| 'NA'                           | 'IO'       | 'IND SMD 1UH 20% 24A(EM-10AM34VG1)'             | 'CHIP'         | ''          | ''   | '20191209'  
 'MMZ1608D500CT/500MA'          | 'SMLF'     | 'IND'    | 'CX08D500000'(!)           = ''              | 'End of Life'      | 'CX08D500000'              |'L0603_EOL'| 'MMZ1608D500CT/500MA'          | 'DISCRETE' | 'EMI FILTER CHIP MMZ1608D500CT(50,500MA)'       | 'CHIP'         | ''          | ''   | '20191210'  
 'MMZ1608D500CT/500MA'          | 'SMLF'     | 'EMPTY'  | 'CX08D500000'(!)           = ''              | 'End of Life'      | 'CX08D500000'              |'L0603_EOL'| 'NA'                           | 'IO'       | 'EMI FILTER CHIP MMZ1608D500CT(50,500MA)'       | 'CHIP'         | ''          | ''   | '20191210'  
 '5.6NH/0.75A'                  | 'SMLF'     | 'IND'    | 'CVB5608TN02'(!)           = ''              | ''                 | 'CVB5608TN02'              |'L0603_H40'| '5.6NH/0.75A'                  | 'DISCRETE' | 'IND CHIP 5.6N+-0.2N 0.75A(LQW18AN5N6C00D'      | 'CHIP'         | ''          | ''   | '20191210'  
 '5.6NH/0.75A'                  | 'SMLF'     | 'EMPTY'  | 'CVB5608TN02'(!)           = ''              | ''                 | 'CVB5608TN02'              |'L0603_H40'| 'NA'                           | 'IO'       | 'IND CHIP 5.6N+-0.2N 0.75A(LQW18AN5N6C00D'      | 'CHIP'         | ''          | ''   | '20191210'  
 '0.42UH/22A'                   | 'SMLF'     | 'IND'    | 'CV+42M0MZ03'(!)           = ''              | ''                 | 'CV+42M0MZ03'              |'L_VCMT063T-2R2MN5_H158'| '0.42UH/22A'                   | 'DISCRETE' | 'IND SMD 0.42UH +-20% 22A(PCME064T-R42M)'       | 'CHIP'         | ''          | ''   | '20191231'  
 '0.42UH/22A'                   | 'SMLF'     | 'EMPTY'  | 'CV+42M0MZ03'(!)           = ''              | ''                 | 'CV+42M0MZ03'              |'L_VCMT063T-2R2MN5_H158'| 'NA'                           | 'IO'       | 'IND SMD 0.42UH +-20% 22A(PCME064T-R42M)'       | 'CHIP'         | ''          | ''   | '20191231'  
 '0.68UH/10.2A'                 | 'SMLF'     | 'IND'    | 'CV+68A2MZ00'(!)           = ''              | ''                 | 'CV+68A2MZ00'              |'L_MMD-05CZ-3R3M-M2Q'| '0.68UH/10.2A'                 | 'DISCRETE' | 'IND SMD 0.68UH20%10.2A MMD-05CZ-R68M-V1Q'      | 'CHIP'         | ''          | ''   | '20191231'  
 '0.68UH/10.2A'                 | 'SMLF'     | 'EMPTY'  | 'CV+68A2MZ00'(!)           = ''              | ''                 | 'CV+68A2MZ00'              |'L_MMD-05CZ-3R3M-M2Q'| 'NA'                           | 'IO'       | 'IND SMD 0.68UH20%10.2A MMD-05CZ-R68M-V1Q'      | 'CHIP'         | ''          | ''   | '20191231'  
 '2.2UH/5.8A'                   | 'SMLF'     | 'IND'    | 'CV-2258MZ05'(!)           = ''              | ''                 | 'CV-2258MZ05'              |'L_MMD-05CZ-3R3M-M2Q'| '2.2UH/5.8A'                   | 'DISCRETE' | 'IND SMD 2.2UH 20% 5.8A(MMD-05CZ-2R2M-V1Q'      | 'CHIP'         | ''          | ''   | '20200102'  
 '2.2UH/5.8A'                   | 'SMLF'     | 'EMPTY'  | 'CV-2258MZ05'(!)           = ''              | ''                 | 'CV-2258MZ05'              |'L_MMD-05CZ-3R3M-M2Q'| 'NA'                           | 'IO'       | 'IND SMD 2.2UH 20% 5.8A(MMD-05CZ-2R2M-V1Q'      | 'CHIP'         | ''          | ''   | '20200102'  
 'BLM31SN500SN1L/10A'           | 'SMLF'     | 'IND'    | 'CX1SN500001'(!)           = ''              | ''                 | 'CX1SN500001'              |'L1206XG'| 'BLM31SN500SN1L/10A'           | 'DISCRETE' | 'EMI FILTER BEAD BLM31SN500SN1L(50,10A)'        | 'CHIP'         | ''          | ''   | '20200109'  
 'BLM31SN500SN1L/10A'           | 'SMLF'     | 'EMPTY'  | 'CX1SN500001'(!)           = ''              | ''                 | 'CX1SN500001'              |'L1206XG'| 'NA'                           | 'IO'       | 'EMI FILTER BEAD BLM31SN500SN1L(50,10A)'        | 'CHIP'         | ''          | ''   | '20200109'  
 '120NH/103A'                   | 'SMLF'     | 'IND'    | 'CV+12^0TZ03'(!)           = ''              | ''                 | 'CV+12^0TZ03'              |'L_HCME1012Q-121QL_10X6'| '120NH/103A'                   | 'DISCRETE' | 'IND SMD 120NH 15% 103A(HCME1012Q)1MHZ'         | 'CHIP'         | ''          | ''   | '20200117'  
 '120NH/103A'                   | 'SMLF'     | 'EMPTY'  | 'CV+12^0TZ03'(!)           = ''              | ''                 | 'CV+12^0TZ03'              |'L_HCME1012Q-121QL_10X6'| 'NA'                           | 'IO'       | 'IND SMD 120NH 15% 103A(HCME1012Q)1MHZ'         | 'CHIP'         | ''          | ''   | '20200117'  
 '50NH/148A'                    | 'SMLF'     | 'IND'    | 'CVA50^0TZ00'(!)           = ''              | ''                 | 'CVA50^0TZ00'              |'L_HCBS1080-500QL_10X8-3'| '50NH/148A'                    | 'DISCRETE' | 'IND SMD 50NH 15% 148A(HCBS1080-500QL)'         | 'CHIP'         | ''          | ''   | '20200207'  
 '50NH/148A'                    | 'SMLF'     | 'EMPTY'  | 'CVA50^0TZ00'(!)           = ''              | ''                 | 'CVA50^0TZ00'              |'L_HCBS1080-500QL_10X8-3'| 'NA'                           | 'IO'       | 'IND SMD 50NH 15% 148A(HCBS1080-500QL)'         | 'CHIP'         | ''          | ''   | '20200207'  
 '120NH/107A'                   | 'SMLF'     | 'IND'    | 'CV+12^0TZ04'(!)           = ''              | ''                 | 'CV+12^0TZ04'              |'L_L101247A-120L_10X6-4'| '120NH/107A'                   | 'DISCRETE' | 'IND SMD 120NH 15% 107A(L101247A-120L)'         | 'CHIP'         | ''          | ''   | '20200210'  
 '120NH/107A'                   | 'SMLF'     | 'EMPTY'  | 'CV+12^0TZ04'(!)           = ''              | ''                 | 'CV+12^0TZ04'              |'L_L101247A-120L_10X6-4'| 'NA'                           | 'IO'       | 'IND SMD 120NH 15% 107A(L101247A-120L)'         | 'CHIP'         | ''          | ''   | '20200210'  
 '120NH/94A'                    | 'SMLF'     | 'IND'    | 'CV+12^0KZ14'(!)           = ''              | ''                 | 'CV+12^0KZ14'              |'L_AF13A-120K_9-6X6-4'| '120NH/94A'                    | 'DISCRETE' | 'IND SMD 120NH 10% 94A(AF13A-120K)'             | 'CHIP'         | ''          | ''   | '20200210'  
 '120NH/94A'                    | 'SMLF'     | 'EMPTY'  | 'CV+12^0KZ14'(!)           = ''              | ''                 | 'CV+12^0KZ14'              |'L_AF13A-120K_9-6X6-4'| 'NA'                           | 'IO'       | 'IND SMD 120NH 10% 94A(AF13A-120K)'             | 'CHIP'         | ''          | ''   | '20200210'  
 '0.12UH/105A'                  | 'SMLF'     | 'IND'    | 'CV+12^0TZ00'(!)           = 'End of Design' | 'Comp-Approve'     | 'CV+12^0TZ00'              |'L_HCME1012Q-121QL_10X6'| '0.12UH/105A'                  | 'DISCRETE' | 'IND SMD 0.12UH +-15% 105A(PA4990.121HLT)'      | 'CHIP'         | ''          | ''   | '20200219'  
 '0.12UH/105A'                  | 'SMLF'     | 'EMPTY'  | 'CV+12^0TZ00'(!)           = 'End of Design' | 'Comp-Approve'     | 'CV+12^0TZ00'              |'L_HCME1012Q-121QL_10X6'| 'NA'                           | 'IO'       | 'IND SMD 0.12UH +-15% 105A(PA4990.121HLT)'      | 'CHIP'         | ''          | ''   | '20200219'  
 '0.33UH/40A'                   | 'SMLF'     | 'IND'    | 'CV+33^0TZ00'(!)           = 'End of Design' | 'Comp-Approve'     | 'CV+33^0TZ00'              |'L_HCME1012Q-121QL_10X6'| '0.33UH/40A'                   | 'DISCRETE' | 'IND SMD 0.33UH +-15% 40A(PA4990.331HLT)'       | 'CHIP'         | ''          | ''   | '20200219'  
 '0.33UH/40A'                   | 'SMLF'     | 'EMPTY'  | 'CV+33^0TZ00'(!)           = 'End of Design' | 'Comp-Approve'     | 'CV+33^0TZ00'              |'L_HCME1012Q-121QL_10X6'| 'NA'                           | 'IO'       | 'IND SMD 0.33UH +-15% 40A(PA4990.331HLT)'       | 'CHIP'         | ''          | ''   | '20200219'  
 '1.0UH/8.5A'                   | 'SMLF'     | 'IND'    | 'CV-1085MZ05'(!)           = ''              | ''                 | 'CV-1085MZ05'              |'L_HCM0503_5-15X5-1'| '1.0UH/8.5A'                   | 'DISCRETE' | 'IND SMD 1.0UH +-20% 8.5A(HCM0503-1R0-R)'       | 'CHIP'         | ''          | ''   | '20200219'  
 '1.0UH/8.5A'                   | 'SMLF'     | 'EMPTY'  | 'CV-1085MZ05'(!)           = ''              | ''                 | 'CV-1085MZ05'              |'L_HCM0503_5-15X5-1'| 'NA'                           | 'IO'       | 'IND SMD 1.0UH +-20% 8.5A(HCM0503-1R0-R)'       | 'CHIP'         | ''          | ''   | '20200219'  
 '150NH/60A'                    | 'SMLF'     | 'IND'    | 'CV+15^0KZ20'(!)           = ''              | ''                 | 'CV+15^0KZ20'              |'L_AH3740A-100K_9-5X6-4'| '150NH/60A'                    | 'DISCRETE' | 'IND SMD 150NH 10% 60A(AH3740A-150K)'           | 'CHIP'         | ''          | ''   | '20200219'  
 '150NH/60A'                    | 'SMLF'     | 'EMPTY'  | 'CV+15^0KZ20'(!)           = ''              | ''                 | 'CV+15^0KZ20'              |'L_AH3740A-100K_9-5X6-4'| 'NA'                           | 'IO'       | 'IND SMD 150NH 10% 60A(AH3740A-150K)'           | 'CHIP'         | ''          | ''   | '20200219'  
 '55NH/30A'                     | 'SMLF'     | 'IND'    | 'CVA55V0MZ00'(!)           = ''              | ''                 | 'CVA55V0MZ00'              |'L_HCB65-550X_5-5X5-7'| '55NH/30A'                     | 'DISCRETE' | 'IND SMD 55NH +-20% 30A(HCB65-550X)'            | 'CHIP'         | ''          | ''   | '20200219'  
 '55NH/30A'                     | 'SMLF'     | 'EMPTY'  | 'CVA55V0MZ00'(!)           = ''              | ''                 | 'CVA55V0MZ00'              |'L_HCB65-550X_5-5X5-7'| 'NA'                           | 'IO'       | 'IND SMD 55NH +-20% 30A(HCB65-550X)'            | 'CHIP'         | ''          | ''   | '20200219'  
 '90NH/155AA'                   | 'SMLF'     | 'IND'    | 'CVA90^0KZ04'(!)           = ''              | ''                 | 'CVA90^0KZ04'              |'L_HCME107512Q-900QL_10X7-7'| '90NH/155A'                    | 'DISCRETE' | 'IND SMD 90NH 10% 155A(HCME107512Q)1MHZ'        | 'CHIP'         | ''          | ''   | '20200221'  
 '90NH/155AA'                   | 'SMLF'     | 'EMPTY'  | 'CVA90^0KZ04'(!)           = ''              | ''                 | 'CVA90^0KZ04'              |'L_HCME107512Q-900QL_10X7-7'| 'NA'                           | 'IO'       | 'IND SMD 90NH 10% 155A(HCME107512Q)1MHZ'        | 'CHIP'         | ''          | ''   | '20200221'  
 '90NH/137A'                    | 'SMLF'     | 'IND'    | 'CVA90^0KZ05'(!)           = ''              | ''                 | 'CVA90^0KZ05'              |'L_HCUVE768012Q-900QL_7-6X8-3'| '90NH/137A'                    | 'DISCRETE' | 'IND SMD 90NH 10% 137A(HCUVE768012Q)1MHZ'       | 'CHIP'         | ''          | ''   | '20200221'  
 '90NH/137A'                    | 'SMLF'     | 'EMPTY'  | 'CVA90^0KZ05'(!)           = ''              | ''                 | 'CVA90^0KZ05'              |'L_HCUVE768012Q-900QL_7-6X8-3'| 'NA'                           | 'IO'       | 'IND SMD 90NH 10% 137A(HCUVE768012Q)1MHZ'       | 'CHIP'         | ''          | ''   | '20200221'  
 'MPZ2012S300ATD25/6A'          | 'SMLF'     | 'IND'    | 'CX12S300000'(!)           = ''              | ''                 | 'CX12S300000'              |'L0805'| 'MPZ2012S300ATD25/6A'          | 'DISCRETE' | 'EMI FIL MPZ2012S300ATD25(30,6A)'               | 'CHIP'         | ''          | ''   | '20200221'  
 'MPZ2012S300ATD25/6A'          | 'SMLF'     | 'EMPTY'  | 'CX12S300000'(!)           = ''              | ''                 | 'CX12S300000'              |'L0805'| 'NA'                           | 'IO'       | 'EMI FIL MPZ2012S300ATD25(30,6A)'               | 'CHIP'         | ''          | ''   | '20200221'  
 '1UH/20.5A'                    | 'SMLF'     | 'IND'    | 'CV-10K5TZ00'(!)           = 'End of Design' | 'Comp-Approve'     | 'CV-10K5TZ00'              |'L_PA4987_10X7'| '1UH/20.5A'                    | 'DISCRETE' | 'IND SMD 1UH +-15% 20.5A(PA4987.102HLT'         | 'CHIP'         | ''          | ''   | '20200221'  
 '1UH/20.5A'                    | 'SMLF'     | 'EMPTY'  | 'CV-10K5TZ00'(!)           = 'End of Design' | 'Comp-Approve'     | 'CV-10K5TZ00'              |'L_PA4987_10X7'| 'NA'                           | 'IO'       | 'IND SMD 1UH +-15% 20.5A(PA4987.102HLT'         | 'CHIP'         | ''          | ''   | '20200221'  
 '1.0UH/2.66A'                  | 'SMLF'     | 'IND'    | 'CV-1027MZ14'(!)           = ''              | ''                 | 'CV-1027MZ14'              |'L_LD1-1R0-R_4-5X4'| '1.0UH/2.66A'                  | 'DISCRETE' | 'IND SMD 1.0UH +-20% 2.66A(LD1-1R0-R)'          | 'CHIP'         | ''          | ''   | '20200306'  
 '1.0UH/2.66A'                  | 'SMLF'     | 'EMPTY'  | 'CV-1027MZ14'(!)           = ''              | ''                 | 'CV-1027MZ14'              |'L_LD1-1R0-R_4-5X4'| 'NA'                           | 'IO'       | 'IND SMD 1.0UH +-20% 2.66A(LD1-1R0-R)'          | 'CHIP'         | ''          | ''   | '20200306'  
 'BLM15BB121SN1D/300'           | 'SMLF'     | 'IND'    | 'CX5BB121007'(!)           = ''              | ''                 | 'CX5BB121007'              |'L0402'| 'BLM15BB121SN1D/300'           | 'DISCRETE' | 'EMI FILTER BLM15BB121SN1D(120,300)'            | 'CHIP'         | ''          | ''   | '20200316'  
 'BLM15BB121SN1D/300'           | 'SMLF'     | 'EMPTY'  | 'CX5BB121007'(!)           = ''              | ''                 | 'CX5BB121007'              |'L0402'| 'NA'                           | 'IO'       | 'EMI FILTER BLM15BB121SN1D(120,300)'            | 'CHIP'         | ''          | ''   | '20200316'  
 '3.7UH/45A'                    | 'SMLF'     | 'IND'    | 'CV-37^0TZ01'(!)           = ''              | ''                 | 'CV-37^0TZ01'              |'LC_61126_H504'| '3.7UH/45A'                    | 'DISCRETE' | 'IND SMD 3.7UH +15/-30% 45A(61126R04)'          | 'CHIP'         | ''          | ''   | '20200317'  
 '3.7UH/45A'                    | 'SMLF'     | 'EMPTY'  | 'CV-37^0TZ01'(!)           = ''              | ''                 | 'CV-37^0TZ01'              |'LC_61126_H504'| 'NA'                           | 'IO'       | 'IND SMD 3.7UH +15/-30% 45A(61126R04)'          | 'CHIP'         | ''          | ''   | '20200317'  
 'BLM18RK121SN1D/200MA'         | 'SMLF'     | 'IND'    | 'CW8RK121001'(!)           = ''              | ''                 | 'CW8RK121001'              |'L0603'| 'BLM18RK121SN1D/200MA'         | 'DISCRETE' | 'FERRITE BEAD BLM18RK121SN1D(100M)'             | 'CHIP'         | ''          | ''   | '20200320'  
 'BLM18RK121SN1D/200MA'         | 'SMLF'     | 'EMPTY'  | 'CW8RK121001'(!)           = ''              | ''                 | 'CW8RK121001'              |'L0603'| 'NA'                           | 'IO'       | 'FERRITE BEAD BLM18RK121SN1D(100M)'             | 'CHIP'         | ''          | ''   | '20200320'  
 'BLM31PG330SN1L/6A'            | 'SMLF'     | 'IND'    | 'CX1PG330004'(!)           = ''              | ''                 | 'CX1PG330004'              |'L1206XF'| 'BLM31PG330SN1L/6A'            | 'DISCRETE' | 'EMI FILTER CHIP BLM31PG330SN1(33,6A)'          | 'CHIP'         | ''          | ''   | '20200325'  
 'BLM31PG330SN1L/6A'            | 'SMLF'     | 'EMPTY'  | 'CX1PG330004'(!)           = ''              | ''                 | 'CX1PG330004'              |'L1206XF'| 'NA'                           | 'IO'       | 'EMI FILTER CHIP BLM31PG330SN1(33,6A)'          | 'CHIP'         | ''          | ''   | '20200325'  
 '0.47UH/23A'                   | 'SMLF'     | 'IND'    | 'CV+47N0MZ00'(!)           = 'End of Design' | 'Comp-Approve'     | 'CV+47N0MZ00'              |'L_VRMXA'| '0.47UH/23A'                   | 'DISCRETE' | 'IND SMD 0.47UH +-20% 23A(PA0515.471NLT)'       | 'CHIP'         | ''          | ''   | '20200401'  
 '0.47UH/23A'                   | 'SMLF'     | 'EMPTY'  | 'CV+47N0MZ00'(!)           = 'End of Design' | 'Comp-Approve'     | 'CV+47N0MZ00'              |'L_VRMXA'| 'NA'                           | 'IO'       | 'IND SMD 0.47UH +-20% 23A(PA0515.471NLT)'       | 'CHIP'         | ''          | ''   | '20200401'  
 '0.47UH/30A'                   | 'SMLF'     | 'IND'    | 'CV+47V0TZ00'(!)           = ''              | ''                 | 'CV+47V0TZ00'              |'L_MSI-111109-R47L-IS_11-2X11-2'| '0.47UH/30A'                   | 'DISCRETE' | 'IND SMD 0.47UH 15% 30A(MSI-111109-R47L)'       | 'CHIP'         | ''          | ''   | '20200331'  
 '0.47UH/30A'                   | 'SMLF'     | 'EMPTY'  | 'CV+47V0TZ00'(!)           = ''              | ''                 | 'CV+47V0TZ00'              |'L_MSI-111109-R47L-IS_11-2X11-2'| 'NA'                           | 'IO'       | 'IND SMD 0.47UH 15% 30A(MSI-111109-R47L)'       | 'CHIP'         | ''          | ''   | '20200331'  
 '0.12UH/69A'                   | 'SMLF'     | 'IND'    | 'CV+12^0TZ05'(!)           = ''              | ''                 | 'CV+12^0TZ05'              |'L_VLBU6565100T-R12L_6-5X6-5'| '0.12UH/69A'                   | 'DISCRETE' | 'IND SMD 0.12UH 15% 69A(VLBU6565100T-R12L'      | 'CHIP'         | ''          | ''   | '20200421'  
 '0.12UH/69A'                   | 'SMLF'     | 'EMPTY'  | 'CV+12^0TZ05'(!)           = ''              | ''                 | 'CV+12^0TZ05'              |'L_VLBU6565100T-R12L_6-5X6-5'| 'NA'                           | 'IO'       | 'IND SMD 0.12UH 15% 69A(VLBU6565100T-R12L'      | 'CHIP'         | ''          | ''   | '20200421'  
 '90NH/155A'                    | 'SMLF'     | 'IND'    | 'CVA90^0KZ08'(!)           = ''              | ''                 | 'CVA90^0KZ08'              |'L_HCME107512Q-900QL_10X7-7'| '90NH/155A'                    | 'DISCRETE' | 'IND SMD 90NH 10% 155A(MSI-100812V-90NK)'       | 'CHIP'         | ''          | ''   | '20200420'  
 '90NH/155A'                    | 'SMLF'     | 'EMPTY'  | 'CVA90^0KZ08'(!)           = ''              | ''                 | 'CVA90^0KZ08'              |'L_HCME107512Q-900QL_10X7-7'| 'NA'                           | 'IO'       | 'IND SMD 90NH 10% 155A(MSI-100812V-90NK)'       | 'CHIP'         | ''          | ''   | '20200420'  
 '90NH/137A'                    | 'SMLF'     | 'IND'    | 'CVA90^0KZ09'(!)           = ''              | ''                 | 'CVA90^0KZ09'              |'L_HCUVE768012Q-900QL_7-6X8-3'| '90NH/137A'                    | 'DISCRETE' | 'IND SMD 90NH 10% 137A(MSI-800812V-90NK)'       | 'CHIP'         | ''          | ''   | '20200420'  
 '90NH/137A'                    | 'SMLF'     | 'EMPTY'  | 'CVA90^0KZ09'(!)           = ''              | ''                 | 'CVA90^0KZ09'              |'L_HCUVE768012Q-900QL_7-6X8-3'| 'NA'                           | 'IO'       | 'IND SMD 90NH 10% 137A(MSI-800812V-90NK)'       | 'CHIP'         | ''          | ''   | '20200420'  
 '90NH/138A'                    | 'SMLF'     | 'IND'    | 'CVA90^0TZ00'(!)           = ''              | ''                 | 'CVA90^0TZ00'              |'L_VLBU12060120R09LF3_12X6'| '90NH/138A'                    | 'DISCRETE' | 'IND SMD 90NH+-15%138A(VLBU12060120R09LF3'      | 'CHIP'         | ''          | ''   | '20200506'  
 '90NH/138A'                    | 'SMLF'     | 'EMPTY'  | 'CVA90^0TZ00'(!)           = ''              | ''                 | 'CVA90^0TZ00'              |'L_VLBU12060120R09LF3_12X6'| 'NA'                           | 'IO'       | 'IND SMD 90NH+-15%138A(VLBU12060120R09LF3'      | 'CHIP'         | ''          | ''   | '20200506'  
 '120NH/76A'                    | 'SMLF'     | 'IND'    | 'CV+12^0TZ06'(!)           = ''              | ''                 | 'CV+12^0TZ06'              |'L_HCME0711Q-121LQL_7X6-7'| '120NH/76A'                    | 'DISCRETE' | 'IND SMD 120NH 15% 76A(HCME0711Q-121LQL)'       | 'CHIP'         | ''          | ''   | '20200514'  
 '120NH/76A'                    | 'SMLF'     | 'EMPTY'  | 'CV+12^0TZ06'(!)           = ''              | ''                 | 'CV+12^0TZ06'              |'L_HCME0711Q-121LQL_7X6-7'| 'NA'                           | 'IO'       | 'IND SMD 120NH 15% 76A(HCME0711Q-121LQL)'       | 'CHIP'         | ''          | ''   | '20200514'  
 '1.5UH/1.7A'                   | 'SMLF'     | 'IND'    | 'CV-1517MZ00'(!)           = ''              | ''                 | 'CV-1517MZ00'              |'L_BDHE002012101R5MQ1_2X1-25'| '1.5UH/1.7A'                   | 'DISCRETE' | 'IND SMD 1.5UH20% 1.7A(BDHE002012101R5MQ1'      | 'CHIP'         | ''          | ''   | '20200526'  
 '1.5UH/1.7A'                   | 'SMLF'     | 'EMPTY'  | 'CV-1517MZ00'(!)           = ''              | ''                 | 'CV-1517MZ00'              |'L_BDHE002012101R5MQ1_2X1-25'| 'NA'                           | 'IO'       | 'IND SMD 1.5UH20% 1.7A(BDHE002012101R5MQ1'      | 'CHIP'         | ''          | ''   | '20200526'  
 '1.5UH/1.6A'                   | 'SMLF'     | 'IND'    | 'CV-1516MN00'(!)           = ''              | ''                 | 'CV-1516MN00'              |'L0805'| '1.5UH/1.6A'                   | 'DISCRETE' | 'IND CHIP 1.5UH 20% 1.6A(DFE201210U-1R5M)'      | 'CHIP'         | ''          | ''   | '20200526'  
 '1.5UH/1.6A'                   | 'SMLF'     | 'EMPTY'  | 'CV-1516MN00'(!)           = ''              | ''                 | 'CV-1516MN00'              |'L0805'| 'NA'                           | 'IO'       | 'IND CHIP 1.5UH 20% 1.6A(DFE201210U-1R5M)'      | 'CHIP'         | ''          | ''   | '20200526'  
 '130NH/106A'                   | 'SMLF'     | 'IND'    | 'CV+13^0KZ11'(!)           = 'End of Design' | 'Comp-Approve'     | 'CV+13^0KZ11'              |'L_HCME107512-131_10X7-5'| '130NH/106A'                   | 'DISCRETE' | 'IND SMD 130NH 10% 106A(PG2323.131HLT)'         | 'CHIP'         | ''          | ''   | '20200608'  
 '130NH/106A'                   | 'SMLF'     | 'EMPTY'  | 'CV+13^0KZ11'(!)           = 'End of Design' | 'Comp-Approve'     | 'CV+13^0KZ11'              |'L_HCME107512-131_10X7-5'| 'NA'                           | 'IO'       | 'IND SMD 130NH 10% 106A(PG2323.131HLT)'         | 'CHIP'         | ''          | ''   | '20200608'  
 '130NH/95A'                    | 'SMLF'     | 'IND'    | 'CV+13^0KZ10'(!)           = 'End of Design' | 'Comp-Approve'     | 'CV+13^0KZ10'              |'L_HCUVE768012-171_7-6X8-1'| '130NH/95A'                    | 'DISCRETE' | 'IND SMD 130NH 10% 95A(PGL6076.131HLT)'         | 'CHIP'         | ''          | ''   | '20200608'  
 '130NH/95A'                    | 'SMLF'     | 'EMPTY'  | 'CV+13^0KZ10'(!)           = 'End of Design' | 'Comp-Approve'     | 'CV+13^0KZ10'              |'L_HCUVE768012-171_7-6X8-1'| 'NA'                           | 'IO'       | 'IND SMD 130NH 10% 95A(PGL6076.131HLT)'         | 'CHIP'         | ''          | ''   | '20200608'  
 '90NH/137A'                    | 'SMLF'     | 'IND'    | 'CVA90^0KZ10'(!)           = 'End of Design' | 'Comp-Approve'     | 'CVA90^0KZ10'              |'L_HCUVE768012Q-900QL_7-6X8-3'| '90NH/137A'                    | 'DISCRETE' | 'IND SMD 90NH 10% 137A(PGL6076.900HLT)'         | 'CHIP'         | ''          | ''   | '20200608'  
 '90NH/137A'                    | 'SMLF'     | 'EMPTY'  | 'CVA90^0KZ10'(!)           = 'End of Design' | 'Comp-Approve'     | 'CVA90^0KZ10'              |'L_HCUVE768012Q-900QL_7-6X8-3'| 'NA'                           | 'IO'       | 'IND SMD 90NH 10% 137A(PGL6076.900HLT)'         | 'CHIP'         | ''          | ''   | '20200608'  
 '90NH/140A'                    | 'SMLF'     | 'IND'    | 'CVA90^0EZ00'(!)           = ''              | ''                 | 'CVA90^0EZ00'              |'L_HCME1211GQ-900QL_12X6'| '90NH/140A'                    | 'DISCRETE' | 'IND SMD 90NH 15% 140A(HCME1211GQ-900QL)'       | 'CHIP'         | ''          | ''   | '20200611'  
 '90NH/140A'                    | 'SMLF'     | 'EMPTY'  | 'CVA90^0EZ00'(!)           = ''              | ''                 | 'CVA90^0EZ00'              |'L_HCME1211GQ-900QL_12X6'| 'NA'                           | 'IO'       | 'IND SMD 90NH 15% 140A(HCME1211GQ-900QL)'       | 'CHIP'         | ''          | ''   | '20200611'  
 '50NH/148A'                    | 'SMLF'     | 'IND'    | 'CVA50^0EZ01'(!)           = 'End of Design' | 'Comp-Approve'     | 'CVA50^0EZ01'              |'L_HCBS1080-500QL_10X8-3'| '50NH/148A'                    | 'DISCRETE' | 'IND SMD 50NH 15% 148A(PGL6189.500HLT)'         | 'CHIP'         | ''          | ''   | '20200620'  
 '50NH/148A'                    | 'SMLF'     | 'EMPTY'  | 'CVA50^0EZ01'(!)           = 'End of Design' | 'Comp-Approve'     | 'CVA50^0EZ01'              |'L_HCBS1080-500QL_10X8-3'| 'NA'                           | 'IO'       | 'IND SMD 50NH 15% 148A(PGL6189.500HLT)'         | 'CHIP'         | ''          | ''   | '20200620'  
 '150NH/75A'                    | 'SMLF'     | 'IND'    | 'CV+15^0KZ24'(!)           = ''              | ''                 | 'CV+15^0KZ24'              |'L_AF13A-120K_9-6X6-4'| '150NH/75A'                    | 'DISCRETE' | 'IND SMD 150NH 10% 75A(PG1712.151AHLT)'         | 'CHIP'         | ''          | ''   | '20200703'  
 '150NH/75A'                    | 'SMLF'     | 'EMPTY'  | 'CV+15^0KZ24'(!)           = ''              | ''                 | 'CV+15^0KZ24'              |'L_AF13A-120K_9-6X6-4'| 'NA'                           | 'IO'       | 'IND SMD 150NH 10% 75A(PG1712.151AHLT)'         | 'CHIP'         | ''          | ''   | '20200703'  
 '120NH/94A'                    | 'SMLF'     | 'IND'    | 'CV+12^0KZ16'(!)           = ''              | ''                 | 'CV+12^0KZ16'              |'L_AF13A-120K_9-6X6-4'| '120NH/94A'                    | 'DISCRETE' | 'IND SMD 120NH 10% 94A(PG1712.121AHLT)'         | 'CHIP'         | ''          | ''   | '20200703'  
 '120NH/94A'                    | 'SMLF'     | 'EMPTY'  | 'CV+12^0KZ16'(!)           = ''              | ''                 | 'CV+12^0KZ16'              |'L_AF13A-120K_9-6X6-4'| 'NA'                           | 'IO'       | 'IND SMD 120NH 10% 94A(PG1712.121AHLT)'         | 'CHIP'         | ''          | ''   | '20200703'  
 '90NH/134A'                    | 'SMLF'     | 'IND'    | 'CVA90^0KZ11'(!)           = ''              | ''                 | 'CVA90^0KZ11'              |'L_AF13A-120K_9-6X6-4'| '90NH/134A'                    | 'DISCRETE' | 'IND SMD 90NH 10% 134A(PG1712.900AHLT)'         | 'CHIP'         | ''          | ''   | '20200703'  
 '90NH/134A'                    | 'SMLF'     | 'EMPTY'  | 'CVA90^0KZ11'(!)           = ''              | ''                 | 'CVA90^0KZ11'              |'L_AF13A-120K_9-6X6-4'| 'NA'                           | 'IO'       | 'IND SMD 90NH 10% 134A(PG1712.900AHLT)'         | 'CHIP'         | ''          | ''   | '20200703'  
 '300NH/33A'                    | 'SMLF'     | 'IND'    | 'CV+30Y0KZ05'(!)           = ''              | ''                 | 'CV+30Y0KZ05'              |'L_AF13A-120K_9-6X6-4'| '300NH/33A'                    | 'DISCRETE' | 'IND SMD 300NH 10% 33A(PG1712.301AHLT)'         | 'CHIP'         | ''          | ''   | '20200703'  
 '300NH/33A'                    | 'SMLF'     | 'EMPTY'  | 'CV+30Y0KZ05'(!)           = ''              | ''                 | 'CV+30Y0KZ05'              |'L_AF13A-120K_9-6X6-4'| 'NA'                           | 'IO'       | 'IND SMD 300NH 10% 33A(PG1712.301AHLT)'         | 'CHIP'         | ''          | ''   | '20200703'  
 '220NH/61A'                    | 'SMLF'     | 'IND'    | 'CV+22^0KZ37'(!)           = ''              | ''                 | 'CV+22^0KZ37'              |'L_HCUVE966412D-221'| '220NH/61A'                    | 'DISCRETE' | 'IND SMD 220NH 10% 61A(PGL6216.221HLT)'         | 'CHIP'         | ''          | ''   | '20200707'  
 '220NH/61A'                    | 'SMLF'     | 'EMPTY'  | 'CV+22^0KZ37'(!)           = ''              | ''                 | 'CV+22^0KZ37'              |'L_HCUVE966412D-221'| 'NA'                           | 'IO'       | 'IND SMD 220NH 10% 61A(PGL6216.221HLT)'         | 'CHIP'         | ''          | ''   | '20200707'  
 '50NH/148A'                    | 'SMLF'     | 'IND'    | 'CVA50^0EZ02'(!)           = ''              | ''                 | 'CVA50^0EZ02'              |'L_HCBS1080-500QL_10X8-3'| '50NH/148A'                    | 'DISCRETE' | 'IND SMD 50NH 15% 148A(EB-50CL3SP01)'           | 'CHIP'         | ''          | ''   | '20200714'  
 '50NH/148A'                    | 'SMLF'     | 'EMPTY'  | 'CVA50^0EZ02'(!)           = ''              | ''                 | 'CVA50^0EZ02'              |'L_HCBS1080-500QL_10X8-3'| 'NA'                           | 'IO'       | 'IND SMD 50NH 15% 148A(EB-50CL3SP01)'           | 'CHIP'         | ''          | ''   | '20200714'  
 '70NH/60A'                     | 'SMLF'     | 'IND'    | 'CVA70^0MZ07'(!)           = 'End of Design' | 'Comp-Approve'     | 'CVA70^0MZ07'              |'L_MSI-600607_6-1X6'| '70NH/60A'                     | 'DISCRETE' | 'IND SMD 70NH 20% 60A(PG2292.700HLT)'           | 'CHIP'         | ''          | ''   | '20200727'  
 '70NH/60A'                     | 'SMLF'     | 'EMPTY'  | 'CVA70^0MZ07'(!)           = 'End of Design' | 'Comp-Approve'     | 'CVA70^0MZ07'              |'L_MSI-600607_6-1X6'| 'NA'                           | 'IO'       | 'IND SMD 70NH 20% 60A(PG2292.700HLT)'           | 'CHIP'         | ''          | ''   | '20200727'  
 '50NH/86A'                     | 'SMLF'     | 'IND'    | 'CVA50^0MZ09'(!)           = 'End of Design' | 'Comp-Approve'     | 'CVA50^0MZ09'              |'L_MSI-600607_6-1X6'| '50NH/86A'                     | 'DISCRETE' | 'IND SMD 50NH 20% 86A(PG2292.500HLT)'           | 'CHIP'         | ''          | ''   | '20200727'  
 '50NH/86A'                     | 'SMLF'     | 'EMPTY'  | 'CVA50^0MZ09'(!)           = 'End of Design' | 'Comp-Approve'     | 'CVA50^0MZ09'              |'L_MSI-600607_6-1X6'| 'NA'                           | 'IO'       | 'IND SMD 50NH 20% 86A(PG2292.500HLT)'           | 'CHIP'         | ''          | ''   | '20200727'  
 '1.0UH/50A'                    | 'SMLF'     | 'IND'    | 'CV-10^0MZ03'(!)           = ''              | ''                 | 'CV-10^0MZ03'              |'L_MMD12EZXA'| '1.0UH/50A'                    | 'DISCRETE' | 'IND SMD 1.0UH 20% 50A(MMD-12EZ-1R0M-V1Q)'      | 'CHIP'         | ''          | ''   | '20200727'  
 '1.0UH/50A'                    | 'SMLF'     | 'EMPTY'  | 'CV-10^0MZ03'(!)           = ''              | ''                 | 'CV-10^0MZ03'              |'L_MMD12EZXA'| 'NA'                           | 'IO'       | 'IND SMD 1.0UH 20% 50A(MMD-12EZ-1R0M-V1Q)'      | 'CHIP'         | ''          | ''   | '20200727'  
 '100NH/16A'                    | 'SMLF'     | 'IND'    | 'CV+10G0MZ12'(!)           = 'End of Design' | 'Comp-Approve'     | 'CV+10G0MZ12'              |'L_PG2289101HLT_4-5X4-7'| '100NH/16A'                    | 'DISCRETE' | 'IND SMD 100NH 20% 16A(PG2289.101HLT)'          | 'CHIP'         | ''          | ''   | '20200728'  
 '100NH/16A'                    | 'SMLF'     | 'EMPTY'  | 'CV+10G0MZ12'(!)           = 'End of Design' | 'Comp-Approve'     | 'CV+10G0MZ12'              |'L_PG2289101HLT_4-5X4-7'| 'NA'                           | 'IO'       | 'IND SMD 100NH 20% 16A(PG2289.101HLT)'          | 'CHIP'         | ''          | ''   | '20200728'  
 '120NH/105A'                   | 'SMLF'     | 'IND'    | 'CV+12^0KZ13'(!)           = 'End of Design' | 'Comp-Approve'     | 'CV+12^0KZ13'              |'L_PGL6054121HLT_10X6'| '120NH/105A'                   | 'DISCRETE' | 'IND SMD 120NH +-10% 105A(PGL6054.121HLT)'      | 'CHIP'         | ''          | ''   | '20200727'  
 '120NH/105A'                   | 'SMLF'     | 'EMPTY'  | 'CV+12^0KZ13'(!)           = 'End of Design' | 'Comp-Approve'     | 'CV+12^0KZ13'              |'L_PGL6054121HLT_10X6'| 'NA'                           | 'IO'       | 'IND SMD 120NH +-10% 105A(PGL6054.121HLT)'      | 'CHIP'         | ''          | ''   | '20200727'  
 '320NH/37A'                    | 'SMLF'     | 'IND'    | 'CV+32^0KZ13'(!)           = ''              | ''                 | 'CV+32^0KZ13'              |'L_HCUVE768012-171_7-6X8-1'| '320NH/37A'                    | 'DISCRETE' | 'IND SMD 320NH 10% 37A(HCUVE768012Q-321QL'      | 'CHIP'         | ''          | ''   | '20200803'  
 '320NH/37A'                    | 'SMLF'     | 'EMPTY'  | 'CV+32^0KZ13'(!)           = ''              | ''                 | 'CV+32^0KZ13'              |'L_HCUVE768012-171_7-6X8-1'| 'NA'                           | 'IO'       | 'IND SMD 320NH 10% 37A(HCUVE768012Q-321QL'      | 'CHIP'         | ''          | ''   | '20200803'  
 '320NH/37A'                    | 'SMLF'     | 'IND'    | 'CV+32^0KZ14'(!)           = 'End of Design' | 'P/N Release'      | 'CV+32^0KZ14'              |'L_HCUVE768012-171_7-6X8-1'| '320NH/37A'                    | 'DISCRETE' | 'IND SMD 320NH 10% 37A(PGL6076.321HLT)'         | 'CHIP'         | ''          | ''   | '20200806'  
 '320NH/37A'                    | 'SMLF'     | 'EMPTY'  | 'CV+32^0KZ14'(!)           = 'End of Design' | 'P/N Release'      | 'CV+32^0KZ14'              |'L_HCUVE768012-171_7-6X8-1'| 'NA'                           | 'IO'       | 'IND SMD 320NH 10% 37A(PGL6076.321HLT)'         | 'CHIP'         | ''          | ''   | '20200806'  
 '10UH/15A'                     | 'THLF'     | 'IND'    | 'DC010F0M000'(!)           = ''              | ''                 | 'DC010F0M000'              |'LC36_P21XA'| '10UH/15A'                     | 'DISCRETE' | 'CHOKE 10UH +-20% 15A(PT20096L)'                | 'CHIP'         | ''          | ''   | '20200818'  
 '10UH/15A'                     | 'THLF'     | 'EMPTY'  | 'DC010F0M000'(!)           = ''              | ''                 | 'DC010F0M000'              |'LC36_P21XA'| 'NA'                           | 'IO'       | 'CHOKE 10UH +-20% 15A(PT20096L)'                | 'CHIP'         | ''          | ''   | '20200818'  
 '300NH/37A'                    | 'SMLF'     | 'IND'    | 'CV+30^0KZ18'(!)           = 'End of Design' | 'Comp-Approve'     | 'CV+30^0KZ18'              |'L_HCUVE966412D-221'| '300NH/37A'                    | 'DISCRETE' | 'IND SMD 300NH 10% 37A(PGL6216.301HLT)'         | 'CHIP'         | ''          | ''   | '20200824'  
 '300NH/37A'                    | 'SMLF'     | 'EMPTY'  | 'CV+30^0KZ18'(!)           = 'End of Design' | 'Comp-Approve'     | 'CV+30^0KZ18'              |'L_HCUVE966412D-221'| 'NA'                           | 'IO'       | 'IND SMD 300NH 10% 37A(PGL6216.301HLT)'         | 'CHIP'         | ''          | ''   | '20200824'  
 '270NH/49A'                    | 'SMLF'     | 'IND'    | 'CV+27^0KZ20'(!)           = ''              | ''                 | 'CV+27^0KZ20'              |'L_HCUVE966412D-221'| '270NH/49A'                    | 'DISCRETE' | 'IND SMD 270NH 10% 49A(PGL6216.271HLT)'         | 'CHIP'         | ''          | ''   | '20200824'  
 '270NH/49A'                    | 'SMLF'     | 'EMPTY'  | 'CV+27^0KZ20'(!)           = ''              | ''                 | 'CV+27^0KZ20'              |'L_HCUVE966412D-221'| 'NA'                           | 'IO'       | 'IND SMD 270NH 10% 49A(PGL6216.271HLT)'         | 'CHIP'         | ''          | ''   | '20200824'  
 '0.68UH/34A'                   | 'SMLF'     | 'IND'    | 'CV+68Z0MZ04'(!)           = ''              | ''                 | 'CV+68Z0MZ04'              |'L_CMME104T_10-1X10'| '0.68UH/34A'                   | 'DISCRETE' | 'IND SMD 0.68UH 20% 34A(CMME104T-R68MS1R6'      | 'CHIP'         | ''          | ''   | '20200827'  
 '0.68UH/34A'                   | 'SMLF'     | 'EMPTY'  | 'CV+68Z0MZ04'(!)           = ''              | ''                 | 'CV+68Z0MZ04'              |'L_CMME104T_10-1X10'| 'NA'                           | 'IO'       | 'IND SMD 0.68UH 20% 34A(CMME104T-R68MS1R6'      | 'CHIP'         | ''          | ''   | '20200827'  
 '39NH/200MA'                   | 'SMLF'     | 'IND'    | 'CVA3902JN00'(!)           = ''              | ''                 | 'CVA3902JN00'              |'L0402'| '39NH/200MA'                   | 'DISCRETE' | 'IND CHIP 39NH,+-5%,200MA,LQG15HS39NJ02D'       | 'CHIP'         | ''          | ''   | '20200914'  
 '39NH/200MA'                   | 'SMLF'     | 'EMPTY'  | 'CVA3902JN00'(!)           = ''              | ''                 | 'CVA3902JN00'              |'L0402'| 'NA'                           | 'IO'       | 'IND CHIP 39NH,+-5%,200MA,LQG15HS39NJ02D'       | 'CHIP'         | ''          | ''   | '20200914'  
 '2.7NH/0.55A'                  | 'SMLF'     | 'IND'    | 'CVB2706TN01'(!)           = ''              | ''                 | 'CVB2706TN01'              |'L0201'| '2.7NH/0.55A'                  | 'DISCRETE' | 'IND CHIP 2.7N+-0.1N0.55A(LQP03TQ2N7B02D)'      | 'CHIP'         | ''          | ''   | '20200916'  
 '2.7NH/0.55A'                  | 'SMLF'     | 'EMPTY'  | 'CVB2706TN01'(!)           = ''              | ''                 | 'CVB2706TN01'              |'L0201'| 'NA'                           | 'IO'       | 'IND CHIP 2.7N+-0.1N0.55A(LQP03TQ2N7B02D)'      | 'CHIP'         | ''          | ''   | '20200916'  
 '2.4NH/300MA'                  | 'SMLF'     | 'IND'    | 'CV-2403TZ00'(!)           = ''              | ''                 | 'CV-2403TZ00'              |'L0402'| '2.4NH/300MA'                  | 'DISCRETE' | 'IND SMD 2.4N ��0.3N 300MA LQG15HS2N4S02D'  | 'CHIP'         | ''          | ''   | '20200916'  
 '2.4NH/300MA'                  | 'SMLF'     | 'EMPTY'  | 'CV-2403TZ00'(!)           = ''              | ''                 | 'CV-2403TZ00'              |'L0402'| 'NA'                           | 'IO'       | 'IND SMD 2.4N ��0.3N 300MA LQG15HS2N4S02D'  | 'CHIP'         | ''          | ''   | '20200916'  
 '1.5NH/0.3A'                   | 'SMLF'     | 'IND'    | 'CVB1503TN01'(!)           = ''              | ''                 | 'CVB1503TN01'              |'L0402'| '1.5NH/0.3A'                   | 'DISCRETE' | 'IND CHIP 1.5N(+-0.3N,0.3A)LQG15HS1N5S02D'      | 'CHIP'         | ''          | ''   | '20200916'  
 '1.5NH/0.3A'                   | 'SMLF'     | 'EMPTY'  | 'CVB1503TN01'(!)           = ''              | ''                 | 'CVB1503TN01'              |'L0402'| 'NA'                           | 'IO'       | 'IND CHIP 1.5N(+-0.3N,0.3A)LQG15HS1N5S02D'      | 'CHIP'         | ''          | ''   | '20200916'  
 '18NH/300MA'                   | 'SMLF'     | 'IND'    | 'CVA1803JN02'(!)           = ''              | ''                 | 'CVA1803JN02'              |'L0402'| '18NH/300MA'                   | 'DISCRETE' | 'IND CHIP 18N +-5% 300MA,LQG15HS18NJ02D'        | 'CHIP'         | ''          | ''   | '20200916'  
 '18NH/300MA'                   | 'SMLF'     | 'EMPTY'  | 'CVA1803JN02'(!)           = ''              | ''                 | 'CVA1803JN02'              |'L0402'| 'NA'                           | 'IO'       | 'IND CHIP 18N +-5% 300MA,LQG15HS18NJ02D'        | 'CHIP'         | ''          | ''   | '20200916'  
 '2.2NH/300MA'                  | 'SMLF'     | 'IND'    | 'CVB2203TN02'(!)           = ''              | ''                 | 'CVB2203TN02'              |'L0402'| '2.2NH/300MA'                  | 'DISCRETE' | 'IND 2.2NH(+-0.3N,300MA)LQG15HS2N2S02D'         | 'CHIP'         | ''          | ''   | '20200916'  
 '2.2NH/300MA'                  | 'SMLF'     | 'EMPTY'  | 'CVB2203TN02'(!)           = ''              | ''                 | 'CVB2203TN02'              |'L0402'| 'NA'                           | 'IO'       | 'IND 2.2NH(+-0.3N,300MA)LQG15HS2N2S02D'         | 'CHIP'         | ''          | ''   | '20200916'  
 '1.8NH/0.3A'                   | 'SMLF'     | 'IND'    | 'CVB1803TN26'(!)           = ''              | ''                 | 'CVB1803TN26'              |'L0402'| '1.8NH/0.3A'                   | 'DISCRETE' | 'IND CHIP 1.8N(+-0.3N,0.3A)LQG15HS1N8S02D'      | 'CHIP'         | ''          | ''   | '20200916'  
 '1.8NH/0.3A'                   | 'SMLF'     | 'EMPTY'  | 'CVB1803TN26'(!)           = ''              | ''                 | 'CVB1803TN26'              |'L0402'| 'NA'                           | 'IO'       | 'IND CHIP 1.8N(+-0.3N,0.3A)LQG15HS1N8S02D'      | 'CHIP'         | ''          | ''   | '20200916'  
 '4.7UH/0.84A'                  | 'SMLF'     | 'IND'    | 'CV-4709TZ02'(!)           = ''              | ''                 | 'CV-4709TZ02'              |'L_MSCDRI4D28_H79'| '4.7UH/0.84A'                  | 'DISCRETE' | 'IND SMD 4.7UH 30% 0.84A MSCDRI-4D18-4R7N'      | 'CHIP'         | ''          | ''   | '20200918'  
 '4.7UH/0.84A'                  | 'SMLF'     | 'EMPTY'  | 'CV-4709TZ02'(!)           = ''              | ''                 | 'CV-4709TZ02'              |'L_MSCDRI4D28_H79'| 'NA'                           | 'IO'       | 'IND SMD 4.7UH 30% 0.84A MSCDRI-4D18-4R7N'      | 'CHIP'         | ''          | ''   | '20200918'  
 '82NH/400MA'                   | 'SMLF'     | 'IND'    | 'CVA8204GZ05'(!)           = ''              | ''                 | 'CVA8204GZ05'              |'L0805CSXA'| '82NH/400MA'                   | 'DISCRETE' | 'IND SMD 82NH 2% 400MA(0805CS-820EGTS)'         | 'CHIP'         | ''          | ''   | '20200924'  
 '82NH/400MA'                   | 'SMLF'     | 'EMPTY'  | 'CVA8204GZ05'(!)           = ''              | ''                 | 'CVA8204GZ05'              |'L0805CSXA'| 'NA'                           | 'IO'       | 'IND SMD 82NH 2% 400MA(0805CS-820EGTS)'         | 'CHIP'         | ''          | ''   | '20200924'  
 '4.7UH/6.5A'                   | 'SMLF'     | 'IND'    | 'CV-4765MZ00'(!)           = ''              | ''                 | 'CV-4765MZ00'              |'L_SC2511_6-5X6-5'| '4.7UH/6.5A'                   | 'DISCRETE' | 'IND SMD 4.7UH +-20% 6.5A(SC2511-4R7M)'         | 'CHIP'         | ''          | ''   | '20200924'  
 '4.7UH/6.5A'                   | 'SMLF'     | 'EMPTY'  | 'CV-4765MZ00'(!)           = ''              | ''                 | 'CV-4765MZ00'              |'L_SC2511_6-5X6-5'| 'NA'                           | 'IO'       | 'IND SMD 4.7UH +-20% 6.5A(SC2511-4R7M)'         | 'CHIP'         | ''          | ''   | '20200924'  
 '2.7NH/1A'                     | 'SMLF'     | 'IND'    | 'CVB2710TN00'(!)           = ''              | ''                 | 'CVB2710TN00'              |'L0603'| '2.7NH/1A'                     | 'DISCRETE' | 'IND CHIP 2.7NH +-0.3NH 1A(LQG18HN2N7S00D'      | 'CHIP'         | ''          | ''   | '20201015'  
 '2.7NH/1A'                     | 'SMLF'     | 'EMPTY'  | 'CVB2710TN00'(!)           = ''              | ''                 | 'CVB2710TN00'              |'L0603'| 'NA'                           | 'IO'       | 'IND CHIP 2.7NH +-0.3NH 1A(LQG18HN2N7S00D'      | 'CHIP'         | ''          | ''   | '20201015'  
 '250NH/42A'                    | 'SMLF'     | 'IND'    | 'CV+25^0KZ06'(!)           = ''              | ''                 | 'CV+25^0KZ06'              |'L_HCUVD6270_6-2X5-5XA'| '250NH/42A'                    | 'DISCRETE' | 'IND SMD 250NH 10% 42A(HCUVD6270Q-251AQL)'      | 'CHIP'         | ''          | ''   | '20201023'  
 '250NH/42A'                    | 'SMLF'     | 'EMPTY'  | 'CV+25^0KZ06'(!)           = ''              | ''                 | 'CV+25^0KZ06'              |'L_HCUVD6270_6-2X5-5XA'| 'NA'                           | 'IO'       | 'IND SMD 250NH 10% 42A(HCUVD6270Q-251AQL)'      | 'CHIP'         | ''          | ''   | '20201023'  
 '400NH/41A'                    | 'SMLF'     | 'IND'    | 'CV+40^0KZ08'(!)           = ''              | ''                 | 'CV+40^0KZ08'              |'L_HCUVE117512D'| '400NH/41A'                    | 'DISCRETE' | 'IND SMD 400NH 10% 41A(HCUVE117512Q)1MHZ'       | 'CHIP'         | ''          | ''   | '20201027'  
 '400NH/41A'                    | 'SMLF'     | 'EMPTY'  | 'CV+40^0KZ08'(!)           = ''              | ''                 | 'CV+40^0KZ08'              |'L_HCUVE117512D'| 'NA'                           | 'IO'       | 'IND SMD 400NH 10% 41A(HCUVE117512Q)1MHZ'       | 'CHIP'         | ''          | ''   | '20201027'  
 '120NH/69A'                    | 'SMLF'     | 'IND'    | 'CV+12^0EZ01'(!)           = ''              | ''                 | 'CV+12^0EZ01'              |'L_VLBU6565100T-R12L_6-5X6-5'| '120NH/69A'                    | 'DISCRETE' | 'IND SMD 120NH 15% 69A(PGL6312.121HLT)'         | 'CHIP'         | ''          | ''   | '20201029'  
 '120NH/69A'                    | 'SMLF'     | 'EMPTY'  | 'CV+12^0EZ01'(!)           = ''              | ''                 | 'CV+12^0EZ01'              |'L_VLBU6565100T-R12L_6-5X6-5'| 'NA'                           | 'IO'       | 'IND SMD 120NH 15% 69A(PGL6312.121HLT)'         | 'CHIP'         | ''          | ''   | '20201029'  
 '1.5UH/53A'                    | 'SMLF'     | 'IND'    | 'CV-15^0MZ02'(!)           = ''              | ''                 | 'CV-15^0MZ02'              |'L_EM-15AM17VG1-QS_14-3X12-9'| '1.5UH/53A'                    | 'DISCRETE' | 'IND SMD 1.5UH 20% 53A(EM-15AM17VG1-QS)'        | 'CHIP'         | ''          | ''   | '20201030'  
 '1.5UH/53A'                    | 'SMLF'     | 'EMPTY'  | 'CV-15^0MZ02'(!)           = ''              | ''                 | 'CV-15^0MZ02'              |'L_EM-15AM17VG1-QS_14-3X12-9'| 'NA'                           | 'IO'       | 'IND SMD 1.5UH 20% 53A(EM-15AM17VG1-QS)'        | 'CHIP'         | ''          | ''   | '20201030'  
 '0.12UH/69A'                   | 'SMLF'     | 'IND'    | 'CV+12^0EZ02'(!)           = ''              | ''                 | 'CV+12^0EZ02'              |'L_VLBU6565100T-R12L-1_6-5X6-5'| '0.12UH/69A'                   | 'DISCRETE' | 'IND SMD 0.12UH 15% 69A(VLBU6565100T-1'         | 'CHIP'         | ''          | ''   | '20201106'  
 '0.12UH/69A'                   | 'SMLF'     | 'EMPTY'  | 'CV+12^0EZ02'(!)           = ''              | ''                 | 'CV+12^0EZ02'              |'L_VLBU6565100T-R12L-1_6-5X6-5'| 'NA'                           | 'IO'       | 'IND SMD 0.12UH 15% 69A(VLBU6565100T-1'         | 'CHIP'         | ''          | ''   | '20201106'  
 '120NH/69A'                    | 'SMLF'     | 'IND'    | 'CV+12^0EZ03'(!)           = ''              | ''                 | 'CV+12^0EZ03'              |'L_VLBU6565100T-R12L-1_6-5X6-5'| '120NH/69A'                    | 'DISCRETE' | 'IND SMD 120NH 15% 69A(PGL6312.121AHLT)'        | 'CHIP'         | ''          | ''   | '20201109'  
 '120NH/69A'                    | 'SMLF'     | 'EMPTY'  | 'CV+12^0EZ03'(!)           = ''              | ''                 | 'CV+12^0EZ03'              |'L_VLBU6565100T-R12L-1_6-5X6-5'| 'NA'                           | 'IO'       | 'IND SMD 120NH 15% 69A(PGL6312.121AHLT)'        | 'CHIP'         | ''          | ''   | '20201109'  
 '220NH/40A'                    | 'SMLF'     | 'IND'    | 'CV+22^0EZ02'(!)           = ''              | ''                 | 'CV+22^0EZ02'              |'L_HCME0711Q-121LQL_7X6-7'| '220NH/40A'                    | 'DISCRETE' | 'IND SMD 220NH 15% 40A(HCME0711Q-221LQL)'       | 'CHIP'         | ''          | ''   | '20201116'  
 '220NH/40A'                    | 'SMLF'     | 'EMPTY'  | 'CV+22^0EZ02'(!)           = ''              | ''                 | 'CV+22^0EZ02'              |'L_HCME0711Q-121LQL_7X6-7'| 'NA'                           | 'IO'       | 'IND SMD 220NH 15% 40A(HCME0711Q-221LQL)'       | 'CHIP'         | ''          | ''   | '20201116'  
 '330NH/26A'                    | 'SMLF'     | 'IND'    | 'CV+33R0EZ00'(!)           = ''              | ''                 | 'CV+33R0EZ00'              |'L_HCME0711Q-121LQL_7X6-7'| '330NH/26A'                    | 'DISCRETE' | 'IND SMD 330NH 15% 26A(HCME0711Q-331LQL)'       | 'CHIP'         | ''          | ''   | '20201116'  
 '330NH/26A'                    | 'SMLF'     | 'EMPTY'  | 'CV+33R0EZ00'(!)           = ''              | ''                 | 'CV+33R0EZ00'              |'L_HCME0711Q-121LQL_7X6-7'| 'NA'                           | 'IO'       | 'IND SMD 330NH 15% 26A(HCME0711Q-331LQL)'       | 'CHIP'         | ''          | ''   | '20201116'  
 '120NH/105A'                   | 'SMLF'     | 'IND'    | 'CV+12^0KZ17'(!)           = 'End of Design' | 'Comp-Approve'     | 'CV+12^0KZ17'              |'L_PGL6054121HLT_10X6'| '120NH/105A'                   | 'DISCRETE' | 'IND SMD 120NH 10% 105A(PGL6054.121AHLT)'       | 'CHIP'         | ''          | ''   | '20201218'  
 '120NH/105A'                   | 'SMLF'     | 'EMPTY'  | 'CV+12^0KZ17'(!)           = 'End of Design' | 'Comp-Approve'     | 'CV+12^0KZ17'              |'L_PGL6054121HLT_10X6'| 'NA'                           | 'IO'       | 'IND SMD 120NH 10% 105A(PGL6054.121AHLT)'       | 'CHIP'         | ''          | ''   | '20201218'  
 '800NH/19A'                    | 'SMLF'     | 'IND'    | 'CV+80J0KZ01'(!)           = ''              | ''                 | 'CV+80J0KZ01'              |'L_HCUVD8095D-102KBQL_8X8'| '800NH/19A'                    | 'DISCRETE' | 'IND SMD 800NH 10% 19A(HCUVD8095-801BQL)'       | 'CHIP'         | ''          | ''   | '20201221'  
 '800NH/19A'                    | 'SMLF'     | 'EMPTY'  | 'CV+80J0KZ01'(!)           = ''              | ''                 | 'CV+80J0KZ01'              |'L_HCUVD8095D-102KBQL_8X8'| 'NA'                           | 'IO'       | 'IND SMD 800NH 10% 19A(HCUVD8095-801BQL)'       | 'CHIP'         | ''          | ''   | '20201221'  
 '0.36UH/25A'                   | 'SMLF'     | 'IND'    | 'CV+36Q0MZ07'(!)           = ''              | ''                 | 'CV+36Q0MZ07'              |'L_PCMS063T_6-6X6-6'| '0.36UH/25A'                   | 'DISCRETE' | 'IND SMD 0.36UH20%25A(CMME063T-R36MS)'          | 'CHIP'         | ''          | ''   | '20210108'  
 '0.36UH/25A'                   | 'SMLF'     | 'EMPTY'  | 'CV+36Q0MZ07'(!)           = ''              | ''                 | 'CV+36Q0MZ07'              |'L_PCMS063T_6-6X6-6'| 'NA'                           | 'IO'       | 'IND SMD 0.36UH20%25A(CMME063T-R36MS)'          | 'CHIP'         | ''          | ''   | '20210108'  
 '330NH/26A'                    | 'SMLF'     | 'IND'    | 'CV+33R0EZ01'(!)           = ''              | ''                 | 'CV+33R0EZ01'              |'L_HCME0711Q-121LQL_7X6-7'| '330NH/26A'                    | 'DISCRETE' | 'IND SMD 330NH 15% 26A(MSI-700711VD-R33L)'      | 'CHIP'         | ''          | ''   | '20210114'  
 '330NH/26A'                    | 'SMLF'     | 'EMPTY'  | 'CV+33R0EZ01'(!)           = ''              | ''                 | 'CV+33R0EZ01'              |'L_HCME0711Q-121LQL_7X6-7'| 'NA'                           | 'IO'       | 'IND SMD 330NH 15% 26A(MSI-700711VD-R33L)'      | 'CHIP'         | ''          | ''   | '20210114'  
 '220NH/81A'                    | 'SMLF'     | 'IND'    | 'CV+22^0KZ42'(!)           = 'End of Design' | 'Comp-Approve'     | 'CV+22^0KZ42'              |'L_HCUVE1112D-221_10-7X7-5'| '220NH/81A'                    | 'DISCRETE' | 'IND SMD 220NH 10% 81A(PG2290.221AHLT)'         | 'CHIP'         | ''          | ''   | '20210202'  
 '220NH/81A'                    | 'SMLF'     | 'EMPTY'  | 'CV+22^0KZ42'(!)           = 'End of Design' | 'Comp-Approve'     | 'CV+22^0KZ42'              |'L_HCUVE1112D-221_10-7X7-5'| 'NA'                           | 'IO'       | 'IND SMD 220NH 10% 81A(PG2290.221AHLT)'         | 'CHIP'         | ''          | ''   | '20210202'  
 '220NH/75A'                    | 'SMLF'     | 'IND'    | 'CV+22^0KZ43'(!)           = ''              | ''                 | 'CV+22^0KZ43'              |'L_HCUVE1112D-221_10-7X7-5'| '220NH/75A'                    | 'DISCRETE' | 'IND SMD 220NH 10% 75A(HCUVE117512Q-221QL'      | 'CHIP'         | ''          | ''   | '20210202'  
 '220NH/75A'                    | 'SMLF'     | 'EMPTY'  | 'CV+22^0KZ43'(!)           = ''              | ''                 | 'CV+22^0KZ43'              |'L_HCUVE1112D-221_10-7X7-5'| 'NA'                           | 'IO'       | 'IND SMD 220NH 10% 75A(HCUVE117512Q-221QL'      | 'CHIP'         | ''          | ''   | '20210202'  
 '3.3UH/9.6A'                   | 'SMLF'     | 'IND'    | 'CV-3396MZ00'(!)           = ''              | ''                 | 'CV-3396MZ00'              |'L_PCMS063T_6-6X6-6'| '3.3UH/9.6A'                   | 'DISCRETE' | 'IND SMD 3.3UH 20% 9.6A(CMMH063T-3R3MS)'        | 'CHIP'         | ''          | ''   | '20210219'  
 '3.3UH/9.6A'                   | 'SMLF'     | 'EMPTY'  | 'CV-3396MZ00'(!)           = ''              | ''                 | 'CV-3396MZ00'              |'L_PCMS063T_6-6X6-6'| 'NA'                           | 'IO'       | 'IND SMD 3.3UH 20% 9.6A(CMMH063T-3R3MS)'        | 'CHIP'         | ''          | ''   | '20210219'  
 '1UH/16.5A'                    | 'SMLF'     | 'IND'    | 'CV-10G5MZ01'(!)           = ''              | ''                 | 'CV-10G5MZ01'              |'L_PCMS063T_6-6X6-6'| '1UH/16.5A'                    | 'DISCRETE' | 'IND SMD 1UH 20% 16.5A(CMMH063T-1R0MS)'         | 'CHIP'         | ''          | ''   | '20210219'  
 '1UH/16.5A'                    | 'SMLF'     | 'EMPTY'  | 'CV-10G5MZ01'(!)           = ''              | ''                 | 'CV-10G5MZ01'              |'L_PCMS063T_6-6X6-6'| 'NA'                           | 'IO'       | 'IND SMD 1UH 20% 16.5A(CMMH063T-1R0MS)'         | 'CHIP'         | ''          | ''   | '20210219'  
 '0.33UH/26A'                   | 'SMLF'     | 'IND'    | 'CV+33R0MZ01'(!)           = ''              | ''                 | 'CV+33R0MZ01'              |'L_PCMS063T_6-6X6-6'| '0.33UH/26A'                   | 'DISCRETE' | 'IND SMD 0.33UH 20% 26A(CMMH063T-R33MS)'        | 'CHIP'         | ''          | ''   | '20210219'  
 '0.33UH/26A'                   | 'SMLF'     | 'EMPTY'  | 'CV+33R0MZ01'(!)           = ''              | ''                 | 'CV+33R0MZ01'              |'L_PCMS063T_6-6X6-6'| 'NA'                           | 'IO'       | 'IND SMD 0.33UH 20% 26A(CMMH063T-R33MS)'        | 'CHIP'         | ''          | ''   | '20210219'  
 '3.3UH/7.8A'                   | 'SMLF'     | 'IND'    | 'CV-3378MZ00'(!)           = ''              | ''                 | 'CV-3378MZ00'              |'L_HBMQ053T_5-25X5-2'| '3.3UH/7.8A'                   | 'DISCRETE' | 'IND SMD 3.3UH 20% 7.8A(HBMQ053T- 3R3MT)'       | 'CHIP'         | ''          | ''   | '20210219'  
 '3.3UH/7.8A'                   | 'SMLF'     | 'EMPTY'  | 'CV-3378MZ00'(!)           = ''              | ''                 | 'CV-3378MZ00'              |'L_HBMQ053T_5-25X5-2'| 'NA'                           | 'IO'       | 'IND SMD 3.3UH 20% 7.8A(HBMQ053T- 3R3MT)'       | 'CHIP'         | ''          | ''   | '20210219'  
 '0.12UH/69A'                   | 'SMLF'     | 'IND'    | 'CV+12^0EZ07'(!)           = ''              | ''                 | 'CV+12^0EZ07'              |'L_VLBU6565100T-R12L-1_6-5X6-5'| '0.12UH/69A'                   | 'DISCRETE' | 'IND SMD 0.12UH 15% 69A(VLBU6565100T-R12L'      | 'CHIP'         | ''          | ''   | '20210302'  
 '0.12UH/69A'                   | 'SMLF'     | 'EMPTY'  | 'CV+12^0EZ07'(!)           = ''              | ''                 | 'CV+12^0EZ07'              |'L_VLBU6565100T-R12L-1_6-5X6-5'| 'NA'                           | 'IO'       | 'IND SMD 0.12UH 15% 69A(VLBU6565100T-R12L'      | 'CHIP'         | ''          | ''   | '20210302'  
 '300NH/44A'                    | 'SMLF'     | 'IND'    | 'CV+30^0KZ19'(!)           = ''              | ''                 | 'CV+30^0KZ19'              |'L_HCUVE966412D-221'| '300NH/44A'                    | 'DISCRETE' | 'IND SMD 300NH 10% 44A(HCUVE966412Q-301QL'      | 'CHIP'         | ''          | ''   | '20210315'  
 '300NH/44A'                    | 'SMLF'     | 'EMPTY'  | 'CV+30^0KZ19'(!)           = ''              | ''                 | 'CV+30^0KZ19'              |'L_HCUVE966412D-221'| 'NA'                           | 'IO'       | 'IND SMD 300NH 10% 44A(HCUVE966412Q-301QL'      | 'CHIP'         | ''          | ''   | '20210315'  
 'BLM15PX471SN1D/1000MA'        | 'SMLF'     | 'IND'    | 'CX5PX471000'(!)           = ''              | ''                 | 'CX5PX471000'              |'L0402'| 'BLM15PX471SN1D/1000MA'        | 'DISCRETE' | 'EMI FILTER BLM15PX471SN1D (470,1000MA)'        | 'CHIP'         | ''          | ''   | '20210407'  
 'BLM15PX471SN1D/1000MA'        | 'SMLF'     | 'EMPTY'  | 'CX5PX471000'(!)           = ''              | ''                 | 'CX5PX471000'              |'L0402'| 'NA'                           | 'IO'       | 'EMI FILTER BLM15PX471SN1D (470,1000MA)'        | 'CHIP'         | ''          | ''   | '20210407'  
 'BLM15BB221SN1D/300MA'         | 'SMLF'     | 'IND'    | 'CX5BB221109'(!)           = ''              | ''                 | 'CX5BB221109'              |'L0402'| 'BLM15BB221SN1D/300MA'         | 'DISCRETE' | 'EMI FILTER BLM15BB221SN1D(220,300MA)'          | 'CHIP'         | ''          | ''   | '20210407'  
 'BLM15BB221SN1D/300MA'         | 'SMLF'     | 'EMPTY'  | 'CX5BB221109'(!)           = ''              | ''                 | 'CX5BB221109'              |'L0402'| 'NA'                           | 'IO'       | 'EMI FILTER BLM15BB221SN1D(220,300MA)'          | 'CHIP'         | ''          | ''   | '20210407'  
 '4.7UH/2A'                     | 'SMLF'     | 'IND'    | 'CV-4720MZ05'(!)           = ''              | ''                 | 'CV-4720MZ05'              |'L_BWVC004040184R7M00_4X4'| '4.7UH/2A'                     | 'DISCRETE' | 'IND SMD 4.7UH 20% 2A(BWVC004040184R7M00)'      | 'CHIP'         | ''          | ''   | '20210427'  
 '4.7UH/2A'                     | 'SMLF'     | 'EMPTY'  | 'CV-4720MZ05'(!)           = ''              | ''                 | 'CV-4720MZ05'              |'L_BWVC004040184R7M00_4X4'| 'NA'                           | 'IO'       | 'IND SMD 4.7UH 20% 2A(BWVC004040184R7M00)'      | 'CHIP'         | ''          | ''   | '20210427'  
 'BLM18KG121TN1D/3A'            | 'SMLF'     | 'IND'    | 'CX8KG121001'(!)           = ''              | ''                 | 'CX8KG121001'              |'L0603'| 'BLM18KG121TN1D/3A'            | 'DISCRETE' | 'EMI FILTER BLM18KG121TN1D(120,3A)'             | 'CHIP'         | ''          | ''   | '20210427'  
 'BLM18KG121TN1D/3A'            | 'SMLF'     | 'EMPTY'  | 'CX8KG121001'(!)           = ''              | ''                 | 'CX8KG121001'              |'L0603'| 'NA'                           | 'IO'       | 'EMI FILTER BLM18KG121TN1D(120,3A)'             | 'CHIP'         | ''          | ''   | '20210427'  
 '400NH/32A'                    | 'SMLF'     | 'IND'    | 'CV+40X0KZ00'(!)           = ''              | ''                 | 'CV+40X0KZ00'              |'L_HCUVE966412D-221'| '400NH/32A'                    | 'DISCRETE' | 'IND SMD 400NH 10% 32A(HCUVE966412Q-401QL'      | 'CHIP'         | ''          | ''   | '20210503'  
 '400NH/32A'                    | 'SMLF'     | 'EMPTY'  | 'CV+40X0KZ00'(!)           = ''              | ''                 | 'CV+40X0KZ00'              |'L_HCUVE966412D-221'| 'NA'                           | 'IO'       | 'IND SMD 400NH 10% 32A(HCUVE966412Q-401QL'      | 'CHIP'         | ''          | ''   | '20210503'  
 'BLM18PG330SN1D/3000M'         | 'SMLF'     | 'IND'    | 'CX8PG330007'(!)           = ''              | ''                 | 'CX8PG330007'              |'L0603'| 'BLM18PG330SN1D/3000M'         | 'DISCRETE' | 'FERRITE BEAD BLM18PG330SN1D (3000M)'           | 'CHIP'         | ''          | ''   | '20210505'  
 'BLM18PG330SN1D/3000M'         | 'SMLF'     | 'EMPTY'  | 'CX8PG330007'(!)           = ''              | ''                 | 'CX8PG330007'              |'L0603'| 'NA'                           | 'IO'       | 'FERRITE BEAD BLM18PG330SN1D (3000M)'           | 'CHIP'         | ''          | ''   | '20210505'  
 '120NH/69A'                    | 'SMLF'     | 'IND'    | 'CV+12^0EZ04'(!)           = ''              | ''                 | 'CV+12^0EZ04'              |'L_VLBU6565100T-R12L-1_6-5X6-5'| '120NH/69A'                    | 'DISCRETE' | 'IND SMD 120NH 15% 69A(HCME656510Q-121QL)'      | 'CHIP'         | ''          | ''   | '20210507'  
 '120NH/69A'                    | 'SMLF'     | 'EMPTY'  | 'CV+12^0EZ04'(!)           = ''              | ''                 | 'CV+12^0EZ04'              |'L_VLBU6565100T-R12L-1_6-5X6-5'| 'NA'                           | 'IO'       | 'IND SMD 120NH 15% 69A(HCME656510Q-121QL)'      | 'CHIP'         | ''          | ''   | '20210507'  
 '300NH/33A'                    | 'SMLF'     | 'IND'    | 'CV+30Y0KZ06'(!)           = ''              | ''                 | 'CV+30Y0KZ06'              |'L_HCUVE966490D-121'| '300NH/33A'                    | 'DISCRETE' | 'IND SMD 300NH 10% 33A(HCUVE966490Q-301QL'      | 'CHIP'         | ''          | ''   | '20210507'  
 '300NH/33A'                    | 'SMLF'     | 'EMPTY'  | 'CV+30Y0KZ06'(!)           = ''              | ''                 | 'CV+30Y0KZ06'              |'L_HCUVE966490D-121'| 'NA'                           | 'IO'       | 'IND SMD 300NH 10% 33A(HCUVE966490Q-301QL'      | 'CHIP'         | ''          | ''   | '20210507'  
 '3.3UH/10A'                    | 'SMLF'     | 'IND'    | 'CV-33A0MZ01'(!)           = ''              | ''                 | 'CV-33A0MZ01'              |'L_MMD-10DZ-R45M-X2Q'| '3.3UH/10A'                    | 'DISCRETE' | 'IND SMD 3.3UH20%10A(MMD-10DZ-3R3M-X2Q)'        | 'CHIP'         | ''          | ''   | '20210507'  
 '3.3UH/10A'                    | 'SMLF'     | 'EMPTY'  | 'CV-33A0MZ01'(!)           = ''              | ''                 | 'CV-33A0MZ01'              |'L_MMD-10DZ-R45M-X2Q'| 'NA'                           | 'IO'       | 'IND SMD 3.3UH20%10A(MMD-10DZ-3R3M-X2Q)'        | 'CHIP'         | ''          | ''   | '20210507'  
 'MHC1608P220Z06BP8A0/8A'       | 'SMLF'     | 'IND'    | 'CX220Z06Z00'(!)           = ''              | ''                 | 'CX220Z06Z00'              |'L0603'| 'MHC1608P220Z06BP8A0/8A'       | 'DISCRETE' | 'EMI FILTER MHC1608P220Z06BP8A0(22,8A)'         | 'CHIP'         | ''          | ''   | '20210507'  
 'MHC1608P220Z06BP8A0/8A'       | 'SMLF'     | 'EMPTY'  | 'CX220Z06Z00'(!)           = ''              | ''                 | 'CX220Z06Z00'              |'L0603'| 'NA'                           | 'IO'       | 'EMI FILTER MHC1608P220Z06BP8A0(22,8A)'         | 'CHIP'         | ''          | ''   | '20210507'  
 'BLM18SG330SN1D/5A'            | 'SMLF'     | 'IND'    | 'CX330SN1000'(!)           = ''              | ''                 | 'CX330SN1000'              |'L0603'| 'BLM18SG330SN1D/5A'            | 'DISCRETE' | 'EMI FILTER BEAD BLM18SG330SN1D(33,3.5A)'       | 'CHIP'         | ''          | ''   | '20210507'  
 'BLM18SG330SN1D/5A'            | 'SMLF'     | 'EMPTY'  | 'CX330SN1000'(!)           = ''              | ''                 | 'CX330SN1000'              |'L0603'| 'NA'                           | 'IO'       | 'EMI FILTER BEAD BLM18SG330SN1D(33,3.5A)'       | 'CHIP'         | ''          | ''   | '20210507'  
 '1UH/11A'                      | 'SMLF'     | 'IND'    | 'CV-10B0MZ47'(!)           = ''              | ''                 | 'CV-10B0MZ47'              |'L_DO3316H-102MLD_13-21X9-91'| '1UH/11A'                      | 'DISCRETE' | 'IND SMD 1UH 20% 11A(DO3316H-102MLD)AEC'        | 'CHIP'         | ''          | ''   | '20210511'  
 '1UH/11A'                      | 'SMLF'     | 'EMPTY'  | 'CV-10B0MZ47'(!)           = ''              | ''                 | 'CV-10B0MZ47'              |'L_DO3316H-102MLD_13-21X9-91'| 'NA'                           | 'IO'       | 'IND SMD 1UH 20% 11A(DO3316H-102MLD)AEC'        | 'CHIP'         | ''          | ''   | '20210511'  
 '68NH/69A'                     | 'SMLF'     | 'IND'    | 'CVA68^0KZ00'(!)           = ''              | ''                 | 'CVA68^0KZ00'              |'L_TPI078060L056N_7X8'| '68NH/69A'                     | 'DISCRETE' | 'IND SMD 68NH 10% 69A(TPI078060L068N)'          | 'CHIP'         | ''          | ''   | '20210511'  
 '68NH/69A'                     | 'SMLF'     | 'EMPTY'  | 'CVA68^0KZ00'(!)           = ''              | ''                 | 'CVA68^0KZ00'              |'L_TPI078060L056N_7X8'| 'NA'                           | 'IO'       | 'IND SMD 68NH 10% 69A(TPI078060L068N)'          | 'CHIP'         | ''          | ''   | '20210511'  
 '22UH/3.4A'                    | 'SMLF'     | 'IND'    | 'CV02234MZ00'(!)           = ''              | ''                 | 'CV02234MZ00'              |'L_XAL5050-223MEC_5-28X5-48'| '22UH/3.4A'                    | 'DISCRETE' | 'IND SMD 22U 20% 3.4A(XAL5050-223MEC)AEC'       | 'CHIP'         | ''          | ''   | '20210512'  
 '22UH/3.4A'                    | 'SMLF'     | 'EMPTY'  | 'CV02234MZ00'(!)           = ''              | ''                 | 'CV02234MZ00'              |'L_XAL5050-223MEC_5-28X5-48'| 'NA'                           | 'IO'       | 'IND SMD 22U 20% 3.4A(XAL5050-223MEC)AEC'       | 'CHIP'         | ''          | ''   | '20210512'  
 '150NH/75A'                    | 'SMLF'     | 'IND'    | 'CV+15^0KZ26'(!)           = ''              | ''                 | 'CV+15^0KZ26'              |'L_HCUVE966490D-121'| '150NH/75A'                    | 'DISCRETE' | 'IND SMD 150NH 10% 75A(HCUVE966490Q-151QL'      | 'CHIP'         | ''          | ''   | '20210514'  
 '150NH/75A'                    | 'SMLF'     | 'EMPTY'  | 'CV+15^0KZ26'(!)           = ''              | ''                 | 'CV+15^0KZ26'              |'L_HCUVE966490D-121'| 'NA'                           | 'IO'       | 'IND SMD 150NH 10% 75A(HCUVE966490Q-151QL'      | 'CHIP'         | ''          | ''   | '20210514'  
 '10UH/15A'                     | 'THLF'     | 'IND'    | 'DC010F0M002'(!)           = ''              | ''                 | 'DC010F0M002'              |'LC38_P21'| '10UH/15A'                     | 'DISCRETE' | 'CHOKE 10UH 20% 15A(ZT14C6C6F5D1100MAAC01'      | 'CHIP'         | ''          | ''   | '20210519'  
 '10UH/15A'                     | 'THLF'     | 'EMPTY'  | 'DC010F0M002'(!)           = ''              | ''                 | 'DC010F0M002'              |'LC38_P21'| 'NA'                           | 'IO'       | 'CHOKE 10UH 20% 15A(ZT14C6C6F5D1100MAAC01'      | 'CHIP'         | ''          | ''   | '20210519'  
 '47NH/0.3A'                    | 'SMLF'     | 'IND'    | 'CVA4703JZ03'(!)           = ''              | ''                 | 'CVA4703JZ03'              |'L0603_H40'| '47NH/0.3A'                    | 'DISCRETE' | 'IND SMD 47NH 5% 0.3A(HCI1608LF-47NJ)'          | 'CHIP'         | ''          | ''   | '20210519'  
 '47NH/0.3A'                    | 'SMLF'     | 'EMPTY'  | 'CVA4703JZ03'(!)           = ''              | ''                 | 'CVA4703JZ03'              |'L0603_H40'| 'NA'                           | 'IO'       | 'IND SMD 47NH 5% 0.3A(HCI1608LF-47NJ)'          | 'CHIP'         | ''          | ''   | '20210519'  
 '1.5UH/48A'                    | 'SMLF'     | 'IND'    | 'CV-15Z0MZ00'(!)           = ''              | ''                 | 'CV-15Z0MZ00'              |'L_HCM1305-1R5-R_13-3X12-2'| '1.5UH/48A'                    | 'DISCRETE' | 'IND SMD 1.5UH 20% 48A(HCM1305-1R5-R)'          | 'CHIP'         | ''          | ''   | '20210520'  
 '1.5UH/48A'                    | 'SMLF'     | 'EMPTY'  | 'CV-15Z0MZ00'(!)           = ''              | ''                 | 'CV-15Z0MZ00'              |'L_HCM1305-1R5-R_13-3X12-2'| 'NA'                           | 'IO'       | 'IND SMD 1.5UH 20% 48A(HCM1305-1R5-R)'          | 'CHIP'         | ''          | ''   | '20210520'  
 'HCB1608KF-330T60/6A'          | 'SMLF'     | 'IND'    | 'CX330T60002'(!)           = ''              | ''                 | 'CX330T60002'              |'L0603'| 'HCB1608KF-330T60/6A'          | 'DISCRETE' | 'EMI FILTER HCB1608KF-330T60(33,6A)'            | 'CHIP'         | ''          | ''   | '20210526'  
 'HCB1608KF-330T60/6A'          | 'SMLF'     | 'EMPTY'  | 'CX330T60002'(!)           = ''              | ''                 | 'CX330T60002'              |'L0603'| 'NA'                           | 'IO'       | 'EMI FILTER HCB1608KF-330T60(33,6A)'            | 'CHIP'         | ''          | ''   | '20210526'  
 'HCB3216KF-121T30/3A'          | 'SMLF'     | 'IND'    | 'CX121T30002'(!)           = 'End of Design' | 'Comp-Approve'     | 'CX121T30002'              |'L1206XH'| 'HCB3216KF-121T30/3A'          | 'DISCRETE' | 'EMI FILTER HCB3216KF-121T30(120,3A)'           | 'CHIP'         | ''          | ''   | '20210527'  
 'HCB3216KF-121T30/3A'          | 'SMLF'     | 'EMPTY'  | 'CX121T30002'(!)           = 'End of Design' | 'Comp-Approve'     | 'CX121T30002'              |'L1206XH'| 'NA'                           | 'IO'       | 'EMI FILTER HCB3216KF-121T30(120,3A)'           | 'CHIP'         | ''          | ''   | '20210527'  
 '6.8UH/3.6A'                   | 'SMLF'     | 'IND'    | 'CV-6836MZ00'(!)           = ''              | ''                 | 'CV-6836MZ00'              |'L_HPAL1V0530-6R8-R_5-4X5-2'| '6.8UH/3.6A'                   | 'DISCRETE' | 'IND SMD 6.8U 20% 3.6A(HPAL1V0530-6R8-R)'       | 'CHIP'         | ''          | ''   | '20210527'  
 '6.8UH/3.6A'                   | 'SMLF'     | 'EMPTY'  | 'CV-6836MZ00'(!)           = ''              | ''                 | 'CV-6836MZ00'              |'L_HPAL1V0530-6R8-R_5-4X5-2'| 'NA'                           | 'IO'       | 'IND SMD 6.8U 20% 3.6A(HPAL1V0530-6R8-R)'       | 'CHIP'         | ''          | ''   | '20210527'  
 '2.2UH/7A'                     | 'SMLF'     | 'IND'    | 'CV-2270MZ24'(!)           = ''              | ''                 | 'CV-2270MZ24'              |'L_HPAL1V0530-6R8-R_5-4X5-2'| '2.2UH/7A'                     | 'DISCRETE' | 'IND SMD 2.2U 20% 7A(HPAL1V0530-2R2-R)'         | 'CHIP'         | ''          | ''   | '20210527'  
 '2.2UH/7A'                     | 'SMLF'     | 'EMPTY'  | 'CV-2270MZ24'(!)           = ''              | ''                 | 'CV-2270MZ24'              |'L_HPAL1V0530-6R8-R_5-4X5-2'| 'NA'                           | 'IO'       | 'IND SMD 2.2U 20% 7A(HPAL1V0530-2R2-R)'         | 'CHIP'         | ''          | ''   | '20210527'  
 '3.3UH/7.8A'                   | 'SMLF'     | 'IND'    | 'CV-3378MZ01'(!)           = ''              | ''                 | 'CV-3378MZ01'              |'L_HBMQ053T_5-25X5-2'| '3.3UH/7.8A'                   | 'DISCRETE' | 'IND SMD 3.3UH 20% 7.8A(HBMQ053T-3R3MT)'        | 'CHIP'         | ''          | ''   | '20210531'  
 '3.3UH/7.8A'                   | 'SMLF'     | 'EMPTY'  | 'CV-3378MZ01'(!)           = ''              | ''                 | 'CV-3378MZ01'              |'L_HBMQ053T_5-25X5-2'| 'NA'                           | 'IO'       | 'IND SMD 3.3UH 20% 7.8A(HBMQ053T-3R3MT)'        | 'CHIP'         | ''          | ''   | '20210531'  
 '0.8UH/37.8A'                  | 'SMLF'     | 'IND'    | 'CV+80^8MZ00'(!)           = ''              | ''                 | 'CV+80^8MZ00'              |'L_XAL7070-801MEC_7-2X7-5'| '0.8UH/37.8A'                  | 'DISCRETE' | 'IND SMD0.8UH20% 37.8A(XAL7070-801MEC)AEC'      | 'CHIP'         | ''          | ''   | '20210531'  
 '0.8UH/37.8A'                  | 'SMLF'     | 'EMPTY'  | 'CV+80^8MZ00'(!)           = ''              | ''                 | 'CV+80^8MZ00'              |'L_XAL7070-801MEC_7-2X7-5'| 'NA'                           | 'IO'       | 'IND SMD0.8UH20% 37.8A(XAL7070-801MEC)AEC'      | 'CHIP'         | ''          | ''   | '20210531'  
 '1000NH/17A'                   | 'SMLF'     | 'IND'    | 'CV-10H0KZ04'(!)           = ''              | ''                 | 'CV-10H0KZ04'              |'L_HCUVD8095D-102KBQL_8X8'| '1000NH/17A'                   | 'DISCRETE' | 'IND SMD 1000NH 10% 17A(HCUVD8095Q-102BQL'      | 'CHIP'         | ''          | ''   | '20210601'  
 '1000NH/17A'                   | 'SMLF'     | 'EMPTY'  | 'CV-10H0KZ04'(!)           = ''              | ''                 | 'CV-10H0KZ04'              |'L_HCUVD8095D-102KBQL_8X8'| 'NA'                           | 'IO'       | 'IND SMD 1000NH 10% 17A(HCUVD8095Q-102BQL'      | 'CHIP'         | ''          | ''   | '20210601'  
 '800NH/22A'                    | 'SMLF'     | 'IND'    | 'CV+80M0KZ00'(!)           = ''              | ''                 | 'CV+80M0KZ00'              |'L_HCUVD8095D-102KBQL_8X8'| '800NH/22A'                    | 'DISCRETE' | 'IND SMD 800NH 10% 22A(HCUVD8095Q-801BQL)'      | 'CHIP'         | ''          | ''   | '20210601'  
 '800NH/22A'                    | 'SMLF'     | 'EMPTY'  | 'CV+80M0KZ00'(!)           = ''              | ''                 | 'CV+80M0KZ00'              |'L_HCUVD8095D-102KBQL_8X8'| 'NA'                           | 'IO'       | 'IND SMD 800NH 10% 22A(HCUVD8095Q-801BQL)'      | 'CHIP'         | ''          | ''   | '20210601'  
 'HCB1005KF-101T20/2A'          | 'SMLF'     | 'IND'    | 'CX101T20001'(!)           = ''              | ''                 | 'CX101T20001'              |'L0402_H24'| 'HCB1005KF-101T20/2A'          | 'DISCRETE' | 'EMI FILTER BEAD HCB1005KF-101T20(100,2A)'      | 'CHIP'         | ''          | ''   | '20210624'  
 'HCB1005KF-101T20/2A'          | 'SMLF'     | 'EMPTY'  | 'CX101T20001'(!)           = ''              | ''                 | 'CX101T20001'              |'L0402_H24'| 'NA'                           | 'IO'       | 'EMI FILTER BEAD HCB1005KF-101T20(100,2A)'      | 'CHIP'         | ''          | ''   | '20210624'  
 '0.15UH/38A'                   | 'SMLF'     | 'IND'    | 'CV+15^0MZ63'(!)           = ''              | ''                 | 'CV+15^0MZ63'              |'L_HBTD053T-R15MS_5-1X5-3'| '0.15UH/38A'                   | 'DISCRETE' | 'IND SMD 0.15UH 20%38A(HBTD053T-R15MS)'         | 'CHIP'         | ''          | ''   | '20210624'  
 '0.15UH/38A'                   | 'SMLF'     | 'EMPTY'  | 'CV+15^0MZ63'(!)           = ''              | ''                 | 'CV+15^0MZ63'              |'L_HBTD053T-R15MS_5-1X5-3'| 'NA'                           | 'IO'       | 'IND SMD 0.15UH 20%38A(HBTD053T-R15MS)'         | 'CHIP'         | ''          | ''   | '20210624'  
 '0.24UH/33A'                   | 'SMLF'     | 'IND'    | 'CV+24Y0MZ00'(!)           = ''              | ''                 | 'CV+24Y0MZ00'              |'L_HBTD053T-R24MS_5-1X5-3'| '0.24UH/33A'                   | 'DISCRETE' | 'IND SMD 0.24UH 20% 33A(HBTD053T-R24MS)'        | 'CHIP'         | ''          | ''   | '20210624'  
 '0.24UH/33A'                   | 'SMLF'     | 'EMPTY'  | 'CV+24Y0MZ00'(!)           = ''              | ''                 | 'CV+24Y0MZ00'              |'L_HBTD053T-R24MS_5-1X5-3'| 'NA'                           | 'IO'       | 'IND SMD 0.24UH 20% 33A(HBTD053T-R24MS)'        | 'CHIP'         | ''          | ''   | '20210624'  
 '4.7NH/850MA'                  | 'SMLF'     | 'IND'    | 'CVB4709TN00'(!)           = ''              | ''                 | 'CVB4709TN00'              |'L0603_H40'| '4.7NH/850MA'                  | 'DISCRETE' | 'INDCHIP 4.7N(+-0.5N 850MA) LQW18AN4N7D00'      | 'CHIP'         | ''          | ''   | '20210701'  
 '4.7NH/850MA'                  | 'SMLF'     | 'EMPTY'  | 'CVB4709TN00'(!)           = ''              | ''                 | 'CVB4709TN00'              |'L0603_H40'| 'NA'                           | 'IO'       | 'INDCHIP 4.7N(+-0.5N 850MA) LQW18AN4N7D00'      | 'CHIP'         | ''          | ''   | '20210701'  
 '1.0UH/2.1A'                   | 'SMLF'     | 'IND'    | 'CV-1021TZ02'(!)           = ''              | ''                 | 'CV-1021TZ02'              | 'L_1226AS-H_3X2-8'                | '1.0UH/2.1A'                   | 'DISCRETE' | 'IND SMD 1.0UH 30% 2.1A(1226AS-H-1R0N=P2)'      | 'CHIP'         | ''          | ''   | '20210708'  
 '1.0UH/2.1A'                   | 'SMLF'     | 'EMPTY'  | 'CV-1021TZ02'(!)           = ''              | ''                 | 'CV-1021TZ02'              | 'L_1226AS-H_3X2-8'                | 'NA'                           | 'IO'       | 'IND SMD 1.0UH 30% 2.1A(1226AS-H-1R0N=P2)'      | 'CHIP'         | ''          | ''   | '20210708'  
 'BPH323023W5-400T/15A'         | 'SMLF'     | 'IND'    | 'CX323023000'(!)           = ''              | ''                 | 'CX323023000'              |'L_BPH323023W5-400T_3-08X2-9'| 'BPH323023W5-400T/15A'         | 'DISCRETE' | 'EMI FILTER BEAD BPH323023W5-400T(40,15A)'      | 'CHIP'         | ''          | ''   | '20210720'  
 'BPH323023W5-400T/15A'         | 'SMLF'     | 'EMPTY'  | 'CX323023000'(!)           = ''              | ''                 | 'CX323023000'              |'L_BPH323023W5-400T_3-08X2-9'| 'NA'                           | 'IO'       | 'EMI FILTER BEAD BPH323023W5-400T(40,15A)'      | 'CHIP'         | ''          | ''   | '20210720'  
 '120NH/82A'                    | 'SMLF'     | 'IND'    | 'CV+12^0KZ20'(!)           = ''              | ''                 | 'CV+12^0KZ20'              |'L_HCUVD6270_6-2X5-5XA'| '120NH/82A'                    | 'DISCRETE' | 'IND SMD 120NH 10% 82A(HCUVD6270GQ-121AQL'      | 'CHIP'         | ''          | ''   | '20210720'  
 '120NH/82A'                    | 'SMLF'     | 'EMPTY'  | 'CV+12^0KZ20'(!)           = ''              | ''                 | 'CV+12^0KZ20'              |'L_HCUVD6270_6-2X5-5XA'| 'NA'                           | 'IO'       | 'IND SMD 120NH 10% 82A(HCUVD6270GQ-121AQL'      | 'CHIP'         | ''          | ''   | '20210720'  
 'MPZ1608S600AT/3.5A'           | 'SMLF'     | 'IND'    | 'CX08S600001'(!)           = ''              | ''                 | 'CX08S600001'              |'L0603'| 'MPZ1608S600AT/3.5A'           | 'DISCRETE' | 'EMI FILTER MPZ1608S600AT(60,3.5A,0.02)EP'      | 'CHIP'         | ''          | ''   | '20210730'  
 'MPZ1608S600AT/3.5A'           | 'SMLF'     | 'EMPTY'  | 'CX08S600001'(!)           = ''              | ''                 | 'CX08S600001'              |'L0603'| 'NA'                           | 'IO'       | 'EMI FILTER MPZ1608S600AT(60,3.5A,0.02)EP'      | 'CHIP'         | ''          | ''   | '20210730'  
 '1UH/2.1A'                     | 'SMLF'     | 'IND'    | 'CV-1021TZ00'(!)           = ''              | ''                 | 'CV-1021TZ00'              |'L_NR3015T_3X3'| '1UH/2.1A'                     | 'DISCRETE' | 'IND SMD 1UH +-30% 2.1A(NR3015T1R0N)'           | 'CHIP'         | ''          | ''   | '20210730'  
 '1UH/2.1A'                     | 'SMLF'     | 'EMPTY'  | 'CV-1021TZ00'(!)           = ''              | ''                 | 'CV-1021TZ00'              |'L_NR3015T_3X3'| 'NA'                           | 'IO'       | 'IND SMD 1UH +-30% 2.1A(NR3015T1R0N)'           | 'CHIP'         | ''          | ''   | '20210730'  
 'BLM15BD221SN1D/300MA'         | 'SMLF'     | 'IND'    | 'CX5BD221000'(!)           = ''              | ''                 | 'CX5BD221000'              |'L0402'| 'BLM15BD221SN1D/300MA'         | 'DISCRETE' | 'EMI FILTER BLM15BD221SN1D(220,300MA)'          | 'CHIP'         | ''          | ''   | '20210730'  
 'BLM15BD221SN1D/300MA'         | 'SMLF'     | 'EMPTY'  | 'CX5BD221000'(!)           = ''              | ''                 | 'CX5BD221000'              |'L0402'| 'NA'                           | 'IO'       | 'EMI FILTER BLM15BD221SN1D(220,300MA)'          | 'CHIP'         | ''          | ''   | '20210730'  
 'BLM21SP700SN1D/6A'            | 'SMLF'     | 'IND'    | 'CX700SN1002'(!)           = ''              | ''                 | 'CX700SN1002'              |'L0805'| 'BLM21SP700SN1D/6A'            | 'DISCRETE' | 'EMI FILTER BLM21SP700SN1D(70,6A)'              | 'CHIP'         | ''          | ''   | '20210802'  
 'BLM21SP700SN1D/6A'            | 'SMLF'     | 'EMPTY'  | 'CX700SN1002'(!)           = ''              | ''                 | 'CX700SN1002'              |'L0805'| 'NA'                           | 'IO'       | 'EMI FILTER BLM21SP700SN1D(70,6A)'              | 'CHIP'         | ''          | ''   | '20210802'  
 '4.7UH/710MA'                  | 'SMLF'     | 'IND'    | 'CV-4708MN00'(!)           = ''              | ''                 | 'CV-4708MN00'              |'L_SWF3225CF-4R7M_3-6X2-8'| '4.7UH/710MA'                  | 'DISCRETE' | 'IND CHIP 4.7UH 20%,710MA(SWF3225CF-4R7M)'      | 'CHIP'         | ''          | ''   | '20210805'  
 '4.7UH/710MA'                  | 'SMLF'     | 'EMPTY'  | 'CV-4708MN00'(!)           = ''              | ''                 | 'CV-4708MN00'              |'L_SWF3225CF-4R7M_3-6X2-8'| 'NA'                           | 'IO'       | 'IND CHIP 4.7UH 20%,710MA(SWF3225CF-4R7M)'      | 'CHIP'         | ''          | ''   | '20210805'  
 '0.6UH/2.8A'                   | 'SMLF'     | 'IND'    | 'CV+6028MZ01'(!)           = ''              | ''                 | 'CV+6028MZ01'              |'L_XFL4012_4X4'| '0.6UH/2.8A'                   | 'DISCRETE' | 'IND SMD 0.6UH 20% 2.8A(XFL4012-601MEC)'        | 'CHIP'         | ''          | ''   | '20210817'  
 '0.6UH/2.8A'                   | 'SMLF'     | 'EMPTY'  | 'CV+6028MZ01'(!)           = ''              | ''                 | 'CV+6028MZ01'              |'L_XFL4012_4X4'| 'NA'                           | 'IO'       | 'IND SMD 0.6UH 20% 2.8A(XFL4012-601MEC)'        | 'CHIP'         | ''          | ''   | '20210817'  
 '1.0UH/4.3A'                   | 'SMLF'     | 'IND'    | 'CV-1043MZ07'(!)           = ''              | ''                 | 'CV-1043MZ07'              |'L_NR3015T_3X3_H48'| '1.0UH/4.3A'                   | 'DISCRETE' | 'IND SMD 1.0UH 20% 4.3A(MDMK3030T1R0MM)'        | 'CHIP'         | ''          | ''   | '20210824'  
 '1.0UH/4.3A'                   | 'SMLF'     | 'EMPTY'  | 'CV-1043MZ07'(!)           = ''              | ''                 | 'CV-1043MZ07'              |'L_NR3015T_3X3_H48'| 'NA'                           | 'IO'       | 'IND SMD 1.0UH 20% 4.3A(MDMK3030T1R0MM)'        | 'CHIP'         | ''          | ''   | '20210824'  
 'BLM31KN121SN1L/6A'            | 'SMLF'     | 'IND'    | 'CX1KN121000'(!)           = 'End of Design' | 'Comp-Approve'     | 'CX1KN121000'              |'L1206XA'| 'BLM31KN121SN1L/6A'            | 'DISCRETE' | 'EMI FILTER BEAD BLM31KN121SN1L(120,6A)'        | 'CHIP'         | ''          | ''   | '20210825'  
 'BLM31KN121SN1L/6A'            | 'SMLF'     | 'EMPTY'  | 'CX1KN121000'(!)           = 'End of Design' | 'Comp-Approve'     | 'CX1KN121000'              |'L1206XA'| 'NA'                           | 'IO'       | 'EMI FILTER BEAD BLM31KN121SN1L(120,6A)'        | 'CHIP'         | ''          | ''   | '20210825'  
 'GMLB-160808-0600P-N8/1A'      | 'SMLF'     | 'IND'    | 'CX080600029'(!)           = ''              | ''                 | 'CX080600029'              |'L0603'| 'GMLB-160808-0600P-N8/1A'      | 'DISCRETE' | 'EMI FILTER GMLB-160808-0600P-N8(600,1A)'       | 'CHIP'         | ''          | ''   | '20210902'  
 'GMLB-160808-0600P-N8/1A'      | 'SMLF'     | 'EMPTY'  | 'CX080600029'(!)           = ''              | ''                 | 'CX080600029'              |'L0603'| 'NA'                           | 'IO'       | 'EMI FILTER GMLB-160808-0600P-N8(600,1A)'       | 'CHIP'         | ''          | ''   | '20210902'  
 '0.07UH/166A'                  | 'SMLF'     | 'IND'    | 'CVA70^0EZ00'(!)           = ''              | ''                 | 'CVA70^0EZ00'              |'L_HCME1012Q-700QL_10X6-2'| '0.07UH/166A'                  | 'DISCRETE' | 'IND SMD 0.07UH 15% 166A(HCME1012Q-700QL)'      | 'CHIP'         | ''          | ''   | '20210914'  
 '0.07UH/166A'                  | 'SMLF'     | 'EMPTY'  | 'CVA70^0EZ00'(!)           = ''              | ''                 | 'CVA70^0EZ00'              |'L_HCME1012Q-700QL_10X6-2'| 'NA'                           | 'IO'       | 'IND SMD 0.07UH 15% 166A(HCME1012Q-700QL)'      | 'CHIP'         | ''          | ''   | '20210914'  
 '470NH/27A'                    | 'SMLF'     | 'IND'    | 'CV+47S0KZ00'(!)           = ''              | ''                 | 'CV+47S0KZ00'              |'L_HCUVE966412D-221'| '470NH/27A'                    | 'DISCRETE' | 'IND SMD 470NH 10% 27A(HCUVE966412Q-471QL'      | 'CHIP'         | ''          | ''   | '20210915'  
 '470NH/27A'                    | 'SMLF'     | 'EMPTY'  | 'CV+47S0KZ00'(!)           = ''              | ''                 | 'CV+47S0KZ00'              |'L_HCUVE966412D-221'| 'NA'                           | 'IO'       | 'IND SMD 470NH 10% 27A(HCUVE966412Q-471QL'      | 'CHIP'         | ''          | ''   | '20210915'  
 '220NH/33A'                    | 'SMLF'     | 'IND'    | 'CV+22Y0EZ01'(!)           = ''              | ''                 | 'CV+22Y0EZ01'              |'L_VLBU6565100T-R12L-1_6-5X6-5'| '220NH/33A'                    | 'DISCRETE' | 'IND SMD 220NH 15% 33A(PGL6312.221AHLT)'        | 'CHIP'         | ''          | ''   | '20210915'  
 '220NH/33A'                    | 'SMLF'     | 'EMPTY'  | 'CV+22Y0EZ01'(!)           = ''              | ''                 | 'CV+22Y0EZ01'              |'L_VLBU6565100T-R12L-1_6-5X6-5'| 'NA'                           | 'IO'       | 'IND SMD 220NH 15% 33A(PGL6312.221AHLT)'        | 'CHIP'         | ''          | ''   | '20210915'  
 '3NH/0.67A'                    | 'SMLF'     | 'IND'    | 'CVB3007TN00'(!)           = ''              | ''                 | 'CVB3007TN00'              |'L0603_W1-1'| '3NH/0.67A'                    | 'DISCRETE' | 'IND CHIP 3NH+-0.2NH 0.67A(LQW18AN3N0C80)'      | 'CHIP'         | ''          | ''   | '20210922'  
 '3NH/0.67A'                    | 'SMLF'     | 'EMPTY'  | 'CVB3007TN00'(!)           = ''              | ''                 | 'CVB3007TN00'              |'L0603_W1-1'| 'NA'                           | 'IO'       | 'IND CHIP 3NH+-0.2NH 0.67A(LQW18AN3N0C80)'      | 'CHIP'         | ''          | ''   | '20210922'  
 '90NH/155A'                    | 'SMLF'     | 'IND'    | 'CVA90^0KZ13'(!)           = 'End of Design' | 'Comp-Approve'     | 'CVA90^0KZ13'              |'L_HCME107512Q-900QL_10X7-7'| '90NH/155A'                    | 'DISCRETE' | 'IND SMD 90NH 10% 155A(PG2323.900HLT)'          | 'CHIP'         | ''          | ''   | '20210923'  
 '90NH/155A'                    | 'SMLF'     | 'EMPTY'  | 'CVA90^0KZ13'(!)           = 'End of Design' | 'Comp-Approve'     | 'CVA90^0KZ13'              |'L_HCME107512Q-900QL_10X7-7'| 'NA'                           | 'IO'       | 'IND SMD 90NH 10% 155A(PG2323.900HLT)'          | 'CHIP'         | ''          | ''   | '20210923'  
 '0.22UH/33A'                   | 'SMLF'     | 'IND'    | 'CV+22Y0EZ00'(!)           = ''              | ''                 | 'CV+22Y0EZ00'              |'L_VLBU6565100T-R12L-1_6-5X6-5'| '0.22UH/33A'                   | 'DISCRETE' | 'IND SMD 0.22UH 15% 33A(HCME656510Q-221QL'      | 'CHIP'         | ''          | ''   | '20210928'  
 '0.22UH/33A'                   | 'SMLF'     | 'EMPTY'  | 'CV+22Y0EZ00'(!)           = ''              | ''                 | 'CV+22Y0EZ00'              |'L_VLBU6565100T-R12L-1_6-5X6-5'| 'NA'                           | 'IO'       | 'IND SMD 0.22UH 15% 33A(HCME656510Q-221QL'      | 'CHIP'         | ''          | ''   | '20210928'  
 '470NH/22A'                    | 'SMLF'     | 'IND'    | 'CV+47M0KZ00'(!)           = ''              | ''                 | 'CV+47M0KZ00'              |'L_HCUVD6270_6-2X5-5XA'| '470NH/22A'                    | 'DISCRETE' | 'IND SMD470NH 10% 22ADC(HCUVD6270Q-471AQL'      | 'CHIP'         | ''          | ''   | '20211110'  
 '470NH/22A'                    | 'SMLF'     | 'EMPTY'  | 'CV+47M0KZ00'(!)           = ''              | ''                 | 'CV+47M0KZ00'              |'L_HCUVD6270_6-2X5-5XA'| 'NA'                           | 'IO'       | 'IND SMD470NH 10% 22ADC(HCUVD6270Q-471AQL'      | 'CHIP'         | ''          | ''   | '20211110'  
 '220NH/47A'                    | 'SMLF'     | 'IND'    | 'CV+22^0KZ46'(!)           = ''              | ''                 | 'CV+22^0KZ46'              |'L_HCUVD6270_6-2X5-5XA'| '220NH/47A'                    | 'DISCRETE' | 'IND SMD220NH 10% 47ADC(HCUVD6270Q-221AQL'      | 'CHIP'         | ''          | ''   | '20211110'  
 '220NH/47A'                    | 'SMLF'     | 'EMPTY'  | 'CV+22^0KZ46'(!)           = ''              | ''                 | 'CV+22^0KZ46'              |'L_HCUVD6270_6-2X5-5XA'| 'NA'                           | 'IO'       | 'IND SMD220NH 10% 47ADC(HCUVD6270Q-221AQL'      | 'CHIP'         | ''          | ''   | '20211110'  
 '180NH/60A'                    | 'SMLF'     | 'IND'    | 'CV+18^0KZ23'(!)           = ''              | ''                 | 'CV+18^0KZ23'              |'L_HCUVD6270_6-2X5-5XA'| '180NH/60A'                    | 'DISCRETE' | 'IND SMD180NH 10% 60ADC(HCUVD6270Q-181AQL'      | 'CHIP'         | ''          | ''   | '20211110'  
 '180NH/60A'                    | 'SMLF'     | 'EMPTY'  | 'CV+18^0KZ23'(!)           = ''              | ''                 | 'CV+18^0KZ23'              |'L_HCUVD6270_6-2X5-5XA'| 'NA'                           | 'IO'       | 'IND SMD180NH 10% 60ADC(HCUVD6270Q-181AQL'      | 'CHIP'         | ''          | ''   | '20211110'  
 '1UH/3.1A'                     | 'SMLF'     | 'IND'    | 'CV-1031MN01'(!)           = ''              | ''                 | 'CV-1031MN01'              |'L_DFE201610E_2X1-6'| '1UH/3.1A'                     | 'DISCRETE' | 'IND CHIP 1UH +-20% 3.1A DFE201610E-1R0MC'      | 'CHIP'         | ''          | ''   | '20211124'  
 '1UH/3.1A'                     | 'SMLF'     | 'EMPTY'  | 'CV-1031MN01'(!)           = ''              | ''                 | 'CV-1031MN01'              |'L_DFE201610E_2X1-6'| 'NA'                           | 'IO'       | 'IND CHIP 1UH +-20% 3.1A DFE201610E-1R0MC'      | 'CHIP'         | ''          | ''   | '20211124'  
 'BLM21SP331SN1D/1.9A'          | 'SMLF'     | 'IND'    | 'CX331SN1000'(!)           = ''              | ''                 | 'CX331SN1000'              |'L0805'| 'BLM21SP331SN1D/1.9A'          | 'DISCRETE' | 'EMI FILTER BLM21SP331SN1D(330,1.9A)'           | 'CHIP'         | ''          | ''   | '20211201'  
 'BLM21SP331SN1D/1.9A'          | 'SMLF'     | 'EMPTY'  | 'CX331SN1000'(!)           = ''              | ''                 | 'CX331SN1000'              |'L0805'| 'NA'                           | 'IO'       | 'EMI FILTER BLM21SP331SN1D(330,1.9A)'           | 'CHIP'         | ''          | ''   | '20211201'  
 '1UH/4A'                       | 'SMLF'     | 'IND'    | 'CV-1040MZ13'(!)           = ''              | 'P/N Release'      | 'CV-1040MZ13'              | 'L_DFE201610E_2X1-6_H48'          | '1UH/4A'                       | 'DISCRETE' | 'IND SMD 1UH 20% 4A (DFE201612E-1R0M=P2)'       | 'CHIP'         | ''          | ''   | '20211201'  
 '1UH/4A'                       | 'SMLF'     | 'EMPTY'  | 'CV-1040MZ13'(!)           = ''              | 'P/N Release'      | 'CV-1040MZ13'              | 'L_DFE201610E_2X1-6_H48'          | 'NA'                           | 'IO'       | 'IND SMD 1UH 20% 4A (DFE201612E-1R0M=P2)'       | 'CHIP'         | ''          | ''   | '20211201'  
 '120NH/65A'                    | 'SMLF'     | 'IND'    | 'CV+12^0KZ00'(!)           = ''              | ''                 | 'CV+12^0KZ00'              |'L_HCB106480N'| '120NH/65A'                    | 'DISCRETE' | 'IND SMD 120NH +/-10% 65A(HCB106480N-121)'      | 'CHIP'         | ''          | ''   | '20211209'  
 '120NH/65A'                    | 'SMLF'     | 'EMPTY'  | 'CV+12^0KZ00'(!)           = ''              | ''                 | 'CV+12^0KZ00'              |'L_HCB106480N'| 'NA'                           | 'IO'       | 'IND SMD 120NH +/-10% 65A(HCB106480N-121)'      | 'CHIP'         | ''          | ''   | '20211209'  
 '300NH/26A'                    | 'SMLF'     | 'IND'    | 'CV+30R0KZ00'(!)           = ''              | ''                 | 'CV+30R0KZ00'              |'L_HCB106480N'| '300NH/26A'                    | 'DISCRETE' | 'IND SMD 300NH +/-10% 26A(HCB106480N-301)'      | 'CHIP'         | ''          | ''   | '20211210'  
 '300NH/26A'                    | 'SMLF'     | 'EMPTY'  | 'CV+30R0KZ00'(!)           = ''              | ''                 | 'CV+30R0KZ00'              |'L_HCB106480N'| 'NA'                           | 'IO'       | 'IND SMD 300NH +/-10% 26A(HCB106480N-301)'      | 'CHIP'         | ''          | ''   | '20211210'  
 '120NH/94A'                    | 'SMLF'     | 'IND'    | 'CV+12^0KZ18'(!)           = ''              | ''                 | 'CV+12^0KZ18'              |'L_HCUVE966490D-121'| '120NH/94A'                    | 'DISCRETE' | 'IND SMD 120NH 10% 94A(HCUVE966490Q-121QL'      | 'CHIP'         | ''          | ''   | '20211210'  
 '120NH/94A'                    | 'SMLF'     | 'EMPTY'  | 'CV+12^0KZ18'(!)           = ''              | ''                 | 'CV+12^0KZ18'              |'L_HCUVE966490D-121'| 'NA'                           | 'IO'       | 'IND SMD 120NH 10% 94A(HCUVE966490Q-121QL'      | 'CHIP'         | ''          | ''   | '20211210'  
 'BLM15HG601SN1D/300MA'         | 'SMLF'     | 'IND'    | 'CX5HG601000'(!)           = ''              | ''                 | 'CX5HG601000'              |'L0402'| 'BLM15HG601SN1D/300MA'         | 'DISCRETE' | 'EMI FILTER BLM15HG601SN1D (600,300MA)'         | 'CHIP'         | ''          | ''   | '20211214'  
 'BLM15HG601SN1D/300MA'         | 'SMLF'     | 'EMPTY'  | 'CX5HG601000'(!)           = ''              | ''                 | 'CX5HG601000'              |'L0402'| 'NA'                           | 'IO'       | 'EMI FILTER BLM15HG601SN1D (600,300MA)'         | 'CHIP'         | ''          | ''   | '20211214'  
 '210NH/47A'                    | 'SMLF'     | 'IND'    | 'CV+21^0KZ05'(!)           = ''              | ''                 | 'CV+21^0KZ05'              |'L_HCUVE966490D-121'| '210NH/47A'                    | 'DISCRETE' | 'IND SMD 210NH 10% 47A(HCUVE966490Q-211QL'      | 'CHIP'         | ''          | ''   | '20211213'  
 '210NH/47A'                    | 'SMLF'     | 'EMPTY'  | 'CV+21^0KZ05'(!)           = ''              | ''                 | 'CV+21^0KZ05'              |'L_HCUVE966490D-121'| 'NA'                           | 'IO'       | 'IND SMD 210NH 10% 47A(HCUVE966490Q-211QL'      | 'CHIP'         | ''          | ''   | '20211213'  
 '0.47UH/23A'                   | 'SMLF'     | 'IND'    | 'CV+47N0KZ04'(!)           = ''              | ''                 | 'CV+47N0KZ04'              |'L_HCUVD6270_6-2X5-5XA'| '0.47UH/23A'                   | 'DISCRETE' | 'IND SMD 0.47UH 10%23A (MSI-600607VD-R47K'      | 'CHIP'         | ''          | ''   | '20211217'  
 '0.47UH/23A'                   | 'SMLF'     | 'EMPTY'  | 'CV+47N0KZ04'(!)           = ''              | ''                 | 'CV+47N0KZ04'              |'L_HCUVD6270_6-2X5-5XA'| 'NA'                           | 'IO'       | 'IND SMD 0.47UH 10%23A (MSI-600607VD-R47K'      | 'CHIP'         | ''          | ''   | '20211217'  
 '0.56UH/40A'                   | 'SMLF'     | 'IND'    | 'CV+56^0MZ08'(!)           = ''              | ''                 | 'CV+56^0MZ08'              |'L_MAC-10DZ_11-5X10'| '0.56UH/40A'                   | 'DISCRETE' | 'IND SMD 0.56UH20% 40A(HPCL1V1040-R56-R)'       | 'CHIP'         | ''          | ''   | '20211229'  
 '0.56UH/40A'                   | 'SMLF'     | 'EMPTY'  | 'CV+56^0MZ08'(!)           = ''              | ''                 | 'CV+56^0MZ08'              |'L_MAC-10DZ_11-5X10'| 'NA'                           | 'IO'       | 'IND SMD 0.56UH20% 40A(HPCL1V1040-R56-R)'       | 'CHIP'         | ''          | ''   | '20211229'  
 '5.6NH/1.9A'                   | 'SMLF'     | 'IND'    | 'CVB5619TN00'(!)           = ''              | ''                 | 'CVB5619TN00'              |'L0603_W1-1'| '5.6NH/1.9A'                   | 'DISCRETE' | 'IND CHIP 5.6NH+-0.2NH1.9A LQW18AN5N6C80D'      | 'CHIP'         | ''          | ''   | '20220105'  
 '5.6NH/1.9A'                   | 'SMLF'     | 'EMPTY'  | 'CVB5619TN00'(!)           = ''              | ''                 | 'CVB5619TN00'              |'L0603_W1-1'| 'NA'                           | 'IO'       | 'IND CHIP 5.6NH+-0.2NH1.9A LQW18AN5N6C80D'      | 'CHIP'         | ''          | ''   | '20220105'  
 '2.2NH/3.2A'                   | 'SMLF'     | 'IND'    | 'CVB2232TN00'(!)           = ''              | ''                 | 'CVB2232TN00'              |'L0603_W1-1'| '2.2NH/3.2A'                   | 'DISCRETE' | 'IND CHIP 2.2NH+-0.2NH3.2A LQW18AN2N2C80D'      | 'CHIP'         | ''          | ''   | '20220113'  
 '2.2NH/3.2A'                   | 'SMLF'     | 'EMPTY'  | 'CVB2232TN00'(!)           = ''              | ''                 | 'CVB2232TN00'              |'L0603_W1-1'| 'NA'                           | 'IO'       | 'IND CHIP 2.2NH+-0.2NH3.2A LQW18AN2N2C80D'      | 'CHIP'         | ''          | ''   | '20220113'  
 '2.2UH/8.3A'                   | 'SMLF'     | 'IND'    | 'CV-2283MZ02'(!)           = ''              | ''                 | 'CV-2283MZ02'              |'L_PCMS063T_6-6X6-6_H79'| '2.2UH/8.3A'                   | 'DISCRETE' | 'IND SMD 2.2UH +-20%8.3A(CMME062T-2R2MS)'       | 'CHIP'         | ''          | ''   | '20220207'  
 '2.2UH/8.3A'                   | 'SMLF'     | 'EMPTY'  | 'CV-2283MZ02'(!)           = ''              | ''                 | 'CV-2283MZ02'              |'L_PCMS063T_6-6X6-6_H79'| 'NA'                           | 'IO'       | 'IND SMD 2.2UH +-20%8.3A(CMME062T-2R2MS)'       | 'CHIP'         | ''          | ''   | '20220207'  
 '180NH/95A'                    | 'SMLF'     | 'IND'    | 'CV+18^0KZ24'(!)           = ''              | ''                 | 'CV+18^0KZ24'              |'L_HCUVE1112D-221_10-7X7-5'| '180NH/95A'                    | 'DISCRETE' | 'IND SMD 180NH 10% 95A(HCUVE117512-181RS'       | 'CHIP'         | ''          | ''   | '20220223'  
 '180NH/95A'                    | 'SMLF'     | 'EMPTY'  | 'CV+18^0KZ24'(!)           = ''              | ''                 | 'CV+18^0KZ24'              |'L_HCUVE1112D-221_10-7X7-5'| 'NA'                           | 'IO'       | 'IND SMD 180NH 10% 95A(HCUVE117512-181RS'       | 'CHIP'         | ''          | ''   | '20220223'  
 'HI0805R800R-10/5A'            | 'SMLF'     | 'IND'    | 'CX0R800R000'(!)           = ''              | ''                 | 'CX0R800R000'              |'L0805_H44'| 'HI0805R800R-10/5A'            | 'DISCRETE' | 'EMI FILTER HI0805R800R-10(80,5A)'              | 'CHIP'         | ''          | ''   | '20220224'  
 'HI0805R800R-10/5A'            | 'SMLF'     | 'EMPTY'  | 'CX0R800R000'(!)           = ''              | ''                 | 'CX0R800R000'              |'L0805_H44'| 'NA'                           | 'IO'       | 'EMI FILTER HI0805R800R-10(80,5A)'              | 'CHIP'         | ''          | ''   | '20220224'  
 '1UH/3A'                       | 'SMLF'     | 'IND'    | 'CV-1030MZ02'(!)           = ''              | ''                 | 'CV-1030MZ02'              | 'L_DFE252012C'                    | '1UH/3A'                       | 'DISCRETE' | 'IND SMD 1U +-20% 3A(1239AS-H-1R0M=P2)'         | 'CHIP'         | ''          | ''   | '20220311'  
 '1UH/3A'                       | 'SMLF'     | 'EMPTY'  | 'CV-1030MZ02'(!)           = ''              | ''                 | 'CV-1030MZ02'              | 'L_DFE252012C'                    | 'NA'                           | 'IO'       | 'IND SMD 1U +-20% 3A(1239AS-H-1R0M=P2)'         | 'CHIP'         | ''          | ''   | '20220311'  
 '0.1UH/28.5A'                  | 'SMLF'     | 'IND'    | 'CV+10T5MZ01'(!)           = ''              | ''                 | 'CV+10T5MZ01'              |'L_XAL4020-222MEC'| '0.1UH/28.5A'                  | 'DISCRETE' | 'IND SMD 0.1UH 20% 28.5A(MND-04BAIR10M-XH'      | 'CHIP'         | ''          | ''   | '20220314'  
 '0.1UH/28.5A'                  | 'SMLF'     | 'EMPTY'  | 'CV+10T5MZ01'(!)           = ''              | ''                 | 'CV+10T5MZ01'              |'L_XAL4020-222MEC'| 'NA'                           | 'IO'       | 'IND SMD 0.1UH 20% 28.5A(MND-04BAIR10M-XH'      | 'CHIP'         | ''          | ''   | '20220314'  
 '100NH/123A'                   | 'SMLF'     | 'IND'    | 'CV+10^0EZ06'(!)           = ''              | ''                 | 'CV+10^0EZ06'              |'L_HCME1012Q-121QL_10X6'| '100NH/123A'                   | 'DISCRETE' | 'IND SMD 100NH 15% 123A(HCME1012Q-101QL)'       | 'CHIP'         | ''          | ''   | '20220318'  
 '100NH/123A'                   | 'SMLF'     | 'EMPTY'  | 'CV+10^0EZ06'(!)           = ''              | ''                 | 'CV+10^0EZ06'              |'L_HCME1012Q-121QL_10X6'| 'NA'                           | 'IO'       | 'IND SMD 100NH 15% 123A(HCME1012Q-101QL)'       | 'CHIP'         | ''          | ''   | '20220318'  
 '0.22UH/29A'                   | 'SMLF'     | 'IND'    | 'CV+22U0MZ00'(!)           = ''              | ''                 | 'CV+22U0MZ00'              |'L_HBTD043T-R22MS_4-1X4-1'| '0.22UH/29A'                   | 'DISCRETE' | 'IND SMD 0.22U 20% 29A(HBTD043T-R22MS)'         | 'CHIP'         | ''          | ''   | '20220329'  
 '0.22UH/29A'                   | 'SMLF'     | 'EMPTY'  | 'CV+22U0MZ00'(!)           = ''              | ''                 | 'CV+22U0MZ00'              |'L_HBTD043T-R22MS_4-1X4-1'| 'NA'                           | 'IO'       | 'IND SMD 0.22U 20% 29A(HBTD043T-R22MS)'         | 'CHIP'         | ''          | ''   | '20220329'  
 '0.22UH/26A'                   | 'SMLF'     | 'IND'    | 'CV+22R0MZ00'(!)           = ''              | ''                 | 'CV+22R0MZ00'              |'L_PCMS063T_6-6X6-6'| '0.22UH/26A'                   | 'DISCRETE' | 'IND SMD 0.22UH +-20%26A(CMMS063T-R22MS)'       | 'CHIP'         | ''          | ''   | '20220411'  
 '0.22UH/26A'                   | 'SMLF'     | 'EMPTY'  | 'CV+22R0MZ00'(!)           = ''              | ''                 | 'CV+22R0MZ00'              |'L_PCMS063T_6-6X6-6'| 'NA'                           | 'IO'       | 'IND SMD 0.22UH +-20%26A(CMMS063T-R22MS)'       | 'CHIP'         | ''          | ''   | '20220411'  
 '0.47UH/30A'                   | 'SMLF'     | 'IND'    | 'CV+47V0MZ03'(!)           = ''              | ''                 | 'CV+47V0MZ03'              |'L_PCMS063T_6-6X6-6'| '0.47UH/30A'                   | 'DISCRETE' | 'IND SMD 0.47UH  20% 30A(CMMS063T-R47MS)'       | 'CHIP'         | ''          | ''   | '20220411'  
 '0.47UH/30A'                   | 'SMLF'     | 'EMPTY'  | 'CV+47V0MZ03'(!)           = ''              | ''                 | 'CV+47V0MZ03'              |'L_PCMS063T_6-6X6-6'| 'NA'                           | 'IO'       | 'IND SMD 0.47UH  20% 30A(CMMS063T-R47MS)'       | 'CHIP'         | ''          | ''   | '20220411'  
 'BBUPWN160805260Y00/6A'        | 'SMLF'     | 'IND'    | 'CX05260Y000'(!)           = ''              | ''                 | 'CX05260Y000'              |'L0603_H26'| 'BBUPWN160805260Y00/6A'        | 'DISCRETE' | 'EMI FILTER BBUPWN160805260Y00(26,6A)'          | 'CHIP'         | ''          | ''   | '20220412'  
 'BBUPWN160805260Y00/6A'        | 'SMLF'     | 'EMPTY'  | 'CX05260Y000'(!)           = ''              | ''                 | 'CX05260Y000'              |'L0603_H26'| 'NA'                           | 'IO'       | 'EMI FILTER BBUPWN160805260Y00(26,6A)'          | 'CHIP'         | ''          | ''   | '20220412'  
 '6.8UH/4A'                     | 'SMLF'     | 'IND'    | 'CV-6840MZ00'(!)           = ''              | ''                 | 'CV-6840MZ00'              |'L_PCMB062D'| '6.8UH/4A'                     | 'DISCRETE' | 'IND SMD 6.8UH +-20% 4A PCMB062D-6R8MS'         | 'CHIP'         | ''          | ''   | '20220413'  
 '6.8UH/4A'                     | 'SMLF'     | 'EMPTY'  | 'CV-6840MZ00'(!)           = ''              | ''                 | 'CV-6840MZ00'              |'L_PCMB062D'| 'NA'                           | 'IO'       | 'IND SMD 6.8UH +-20% 4A PCMB062D-6R8MS'         | 'CHIP'         | ''          | ''   | '20220413'  
 '150NH/120A'                   | 'SMLF'     | 'IND'    | 'CV+15^0KZ30'(!)           = ''              | ''                 | 'CV+15^0KZ30'              |'L_HCUVD8095D-102KBQL_8X8'| '150NH/120A'                   | 'DISCRETE' | 'IND SMD 150NH 10% 120A(HCUVD8095G-151QL)'      | 'CHIP'         | ''          | ''   | '20220421'  
 '150NH/120A'                   | 'SMLF'     | 'EMPTY'  | 'CV+15^0KZ30'(!)           = ''              | ''                 | 'CV+15^0KZ30'              |'L_HCUVD8095D-102KBQL_8X8'| 'NA'                           | 'IO'       | 'IND SMD 150NH 10% 120A(HCUVD8095G-151QL)'      | 'CHIP'         | ''          | ''   | '20220421'  
 '2.2UH/16A'                    | 'SMLF'     | 'IND'    | 'CV-22G0MZ09'(!)           = ''              | ''                 | 'CV-22G0MZ09'              |'L_PCMS063T_6-6X6-6'| '2.2UH/16A'                    | 'DISCRETE' | 'IND SMD 2.2UH 20% 16A(CMMS063T-2R2MS)'         | 'CHIP'         | ''          | ''   | '20220421'  
 '2.2UH/16A'                    | 'SMLF'     | 'EMPTY'  | 'CV-22G0MZ09'(!)           = ''              | ''                 | 'CV-22G0MZ09'              |'L_PCMS063T_6-6X6-6'| 'NA'                           | 'IO'       | 'IND SMD 2.2UH 20% 16A(CMMS063T-2R2MS)'         | 'CHIP'         | ''          | ''   | '20220421'  
 'PBY160808T-121Y-N/2.5A'       | 'SMLF'     | 'IND'    | 'CX08T121001'(!)           = ''              | ''                 | 'CX08T121001'              |'L0603'| 'PBY160808T-121Y-N/2.5A'       | 'DISCRETE' | 'EMI FILTER PBY160808T-121Y-N(120,2.5A)'        | 'CHIP'         | ''          | ''   | '20220422'  
 'PBY160808T-121Y-N/2.5A'       | 'SMLF'     | 'EMPTY'  | 'CX08T121001'(!)           = ''              | ''                 | 'CX08T121001'              |'L0603'| 'NA'                           | 'IO'       | 'EMI FILTER PBY160808T-121Y-N(120,2.5A)'        | 'CHIP'         | ''          | ''   | '20220422'  
 '700NH/62A'                    | 'SMLF'     | 'IND'    | 'CV+70^0KZ01'(!)           = ''              | ''                 | 'CV+70^0KZ01'              |'L_HCUVD1115_11X8XA'| '700NH/62A'                    | 'DISCRETE' | 'IND SMD 700NH 10% 62A(HCUVD1115-701QL)'        | 'CHIP'         | ''          | ''   | '20220428'  
 '700NH/62A'                    | 'SMLF'     | 'EMPTY'  | 'CV+70^0KZ01'(!)           = ''              | ''                 | 'CV+70^0KZ01'              |'L_HCUVD1115_11X8XA'| 'NA'                           | 'IO'       | 'IND SMD 700NH 10% 62A(HCUVD1115-701QL)'        | 'CHIP'         | ''          | ''   | '20220428'  
 'HCB1005KF-121T20/2000MA'      | 'SMLF'     | 'IND'    | 'CX121T20005'(!)           = ''              | ''                 | 'CX121T20005'              |'L0402_H24'| 'HCB1005KF-121T20/2000MA'      | 'DISCRETE' | 'EMI FILTER HCB1005KF-121T20(120,2000MA)'       | 'CHIP'         | ''          | ''   | '20220504'  
 'HCB1005KF-121T20/2000MA'      | 'SMLF'     | 'EMPTY'  | 'CX121T20005'(!)           = ''              | ''                 | 'CX121T20005'              |'L0402_H24'| 'NA'                           | 'IO'       | 'EMI FILTER HCB1005KF-121T20(120,2000MA)'       | 'CHIP'         | ''          | ''   | '20220504'  
 'HCB1608KF-121T30/3A'          | 'SMLF'     | 'IND'    | 'CX121T30000'(!)           = ''              | ''                 | 'CX121T30000'              |'L0603'| 'HCB1608KF-121T30/3A'          | 'DISCRETE' | 'EMI FILTER HCB1608KF-121T30(120+-25%,3A)'      | 'CHIP'         | ''          | ''   | '20220504'  
 'HCB1608KF-121T30/3A'          | 'SMLF'     | 'EMPTY'  | 'CX121T30000'(!)           = ''              | ''                 | 'CX121T30000'              |'L0603'| 'NA'                           | 'IO'       | 'EMI FILTER HCB1608KF-121T30(120+-25%,3A)'      | 'CHIP'         | ''          | ''   | '20220504'  
 '1.0UH/24A'                    | 'SMLF'     | 'IND'    | 'CV-10P0MZ08'(!)           = ''              | ''                 | 'CV-10P0MZ08'              |'L_MHD-07EZP_7-2X7-5'| '1.0UH/24A'                    | 'DISCRETE' | 'IND SMD 1.0UH 20% 24A(HM-10AM34VG1-QS)'        | 'CHIP'         | ''          | ''   | '20220505'  
 '1.0UH/24A'                    | 'SMLF'     | 'EMPTY'  | 'CV-10P0MZ08'(!)           = ''              | ''                 | 'CV-10P0MZ08'              |'L_MHD-07EZP_7-2X7-5'| 'NA'                           | 'IO'       | 'IND SMD 1.0UH 20% 24A(HM-10AM34VG1-QS)'        | 'CHIP'         | ''          | ''   | '20220505'  
 'GMLB-201209-0600Y-PY-QU/2A'   | 'SMLF'     | 'IND'    | 'CX090600002'(!)           = ''              | ''                 | 'CX090600002'              |'L0805_H44'| 'GMLB-201209-0600Y-PY-QU/2A'   | 'DISCRETE' | 'EMI FIL GMLB-201209-0600Y-PY-QU (600,2A)'      | 'CHIP'         | ''          | ''   | '20220602'  
 'GMLB-201209-0600Y-PY-QU/2A'   | 'SMLF'     | 'EMPTY'  | 'CX090600002'(!)           = ''              | ''                 | 'CX090600002'              |'L0805_H44'| 'NA'                           | 'IO'       | 'EMI FIL GMLB-201209-0600Y-PY-QU (600,2A)'      | 'CHIP'         | ''          | ''   | '20220602'  
 'BLE32PN300SN1L/10A'           | 'SMLF'     | 'IND'    | 'CX000300000'(!)           = ''              | ''                 | 'CX000300000'              |'L1210XD'| 'BLE32PN300SN1L/10A'           | 'DISCRETE' | 'EMI FILTER BLE32PN300SN1L(30,10A)'             | 'CHIP'         | ''          | ''   | '20220607'  
 'BLE32PN300SN1L/10A'           | 'SMLF'     | 'EMPTY'  | 'CX000300000'(!)           = ''              | ''                 | 'CX000300000'              |'L1210XD'| 'NA'                           | 'IO'       | 'EMI FILTER BLE32PN300SN1L(30,10A)'             | 'CHIP'         | ''          | ''   | '20220607'  
 '220NH/57A'                    | 'SMLF'     | 'IND'    | 'CV+22^0KZ41'(!)           = ''              | ''                 | 'CV+22^0KZ41'              |'L_HCUVE768012-171_7-6X8-1'| '220NH/57A'                    | 'DISCRETE' | 'IND SMD 220NH 10% 57A(HCUVE768012Q-221QL'      | 'CHIP'         | ''          | ''   | '20220607'  
 '220NH/57A'                    | 'SMLF'     | 'EMPTY'  | 'CV+22^0KZ41'(!)           = ''              | ''                 | 'CV+22^0KZ41'              |'L_HCUVE768012-171_7-6X8-1'| 'NA'                           | 'IO'       | 'IND SMD 220NH 10% 57A(HCUVE768012Q-221QL'      | 'CHIP'         | ''          | ''   | '20220607'  
 'BLM15PX331SN1D/1200MA'        | 'SMLF'     | 'IND'    | 'CX5PX331000'(!)           = ''              | ''                 | 'CX5PX331000'              |'L0402'| 'BLM15PX331SN1D/1200MA'        | 'DISCRETE' | 'EMI FILTER BLM15PX331SN1D (330,1200MA)'        | 'CHIP'         | ''          | ''   | '20220609'  
 'BLM15PX331SN1D/1200MA'        | 'SMLF'     | 'EMPTY'  | 'CX5PX331000'(!)           = ''              | ''                 | 'CX5PX331000'              |'L0402'| 'NA'                           | 'IO'       | 'EMI FILTER BLM15PX331SN1D (330,1200MA)'        | 'CHIP'         | ''          | ''   | '20220609'  
 '10UH/23A'                     | 'THLF'     | 'IND'    | 'DC010N0L001'(!)           = ''              | ''                 | 'DC010N0L001'              |'LC_P9W4-3_22X14'| '10UH/23A'                     | 'DISCRETE' | 'CHOKE 10UH 15% 23A(PSC-210160-100 GP'          | 'CHIP'         | ''          | ''   | '20220615'  
 '10UH/23A'                     | 'THLF'     | 'EMPTY'  | 'DC010N0L001'(!)           = ''              | ''                 | 'DC010N0L001'              |'LC_P9W4-3_22X14'| 'NA'                           | 'IO'       | 'CHOKE 10UH 15% 23A(PSC-210160-100 GP'          | 'CHIP'         | ''          | ''   | '20220615'  
 'BLM18KG101TN1D/3A'            | 'SMLF'     | 'IND'    | 'CX8KG101000'(!)           = ''              | ''                 | 'CX8KG101000'              |'L0603'| 'BLM18KG101TN1D/3A'            | 'DISCRETE' | 'EMI FILTER BLM18KG101TN1D (100,3A,0.03)'       | 'CHIP'         | ''          | ''   | '20220624'  
 'BLM18KG101TN1D/3A'            | 'SMLF'     | 'EMPTY'  | 'CX8KG101000'(!)           = ''              | ''                 | 'CX8KG101000'              |'L0603'| 'NA'                           | 'IO'       | 'EMI FILTER BLM18KG101TN1D (100,3A,0.03)'       | 'CHIP'         | ''          | ''   | '20220624'  
 '220NH/42A'                    | 'SMLF'     | 'IND'    | 'CV+22^0KZ50'(!)           = ''              | ''                 | 'CV+22^0KZ50'              |'L_HCME0711Q-221QL_7X6-7'| '220NH/42A'                    | 'DISCRETE' | 'IND SMD 220NH 10% 42A HCME0711Q-221QL'         | 'CHIP'         | ''          | ''   | '20220705'  
 '220NH/42A'                    | 'SMLF'     | 'EMPTY'  | 'CV+22^0KZ50'(!)           = ''              | ''                 | 'CV+22^0KZ50'              |'L_HCME0711Q-221QL_7X6-7'| 'NA'                           | 'IO'       | 'IND SMD 220NH 10% 42A HCME0711Q-221QL'         | 'CHIP'         | ''          | ''   | '20220705'  
 'BBPY00100505102Y00/500MA'     | 'SMLF'     | 'IND'    | 'CX505102000'(!)           = ''              | ''                 | 'CX505102000'              |'L0402_H24'| 'BBPY00100505102Y00/500MA'     | 'DISCRETE' | 'EMI FILTER BBPY00100505102(1K,500MA)SELA'      | 'CHIP'         | ''          | ''   | '20220715'  
 'BBPY00100505102Y00/500MA'     | 'SMLF'     | 'EMPTY'  | 'CX505102000'(!)           = ''              | ''                 | 'CX505102000'              |'L0402_H24'| 'NA'                           | 'IO'       | 'EMI FILTER BBPY00100505102(1K,500MA)SELA'      | 'CHIP'         | ''          | ''   | '20220715'  
 'HCB2012KF-121T25/2.5A'        | 'SMLF'     | 'IND'    | 'CX121T25000'(!)           = ''              | ''                 | 'CX121T25000'              |'L0805'| 'HCB2012KF-121T25/2.5A'        | 'DISCRETE' | 'EMI FILTER HCB2012KF-121T25(120,2.5A)'         | 'CHIP'         | ''          | ''   | '20220808'  
 'HCB2012KF-121T25/2.5A'        | 'SMLF'     | 'EMPTY'  | 'CX121T25000'(!)           = ''              | ''                 | 'CX121T25000'              |'L0805'| 'NA'                           | 'IO'       | 'EMI FILTER HCB2012KF-121T25(120,2.5A)'         | 'CHIP'         | ''          | ''   | '20220808'  
 '0.68UH/17A'                   | 'SMLF'     | 'IND'    | 'CV+68H0MZ03'(!)           = ''              | ''                 | 'CV+68H0MZ03'              |'L_PCMS063T_6-6X6-6_H79'| '0.68UH/17A'                   | 'DISCRETE' | 'IND SMD 0.68UH 20% 17A(CMLE061H-R68MS-01'      | 'CHIP'         | ''          | ''   | '20220818'  
 '0.68UH/17A'                   | 'SMLF'     | 'EMPTY'  | 'CV+68H0MZ03'(!)           = ''              | ''                 | 'CV+68H0MZ03'              |'L_PCMS063T_6-6X6-6_H79'| 'NA'                           | 'IO'       | 'IND SMD 0.68UH 20% 17A(CMLE061H-R68MS-01'      | 'CHIP'         | ''          | ''   | '20220818'  
 '220NH/47A'                    | 'SMLF'     | 'IND'    | 'CV+22^0EZ06'(!)           = ''              | ''                 | 'CV+22^0EZ06'              |'L_HCME706713Q-221QL_7X6-7'| '220NH/47A'                    | 'DISCRETE' | 'IND SMD 220NH 15% 47A(HCME706713Q-221QL)'      | 'CHIP'         | ''          | ''   | '20220818'  
 '220NH/47A'                    | 'SMLF'     | 'EMPTY'  | 'CV+22^0EZ06'(!)           = ''              | ''                 | 'CV+22^0EZ06'              |'L_HCME706713Q-221QL_7X6-7'| 'NA'                           | 'IO'       | 'IND SMD 220NH 15% 47A(HCME706713Q-221QL)'      | 'CHIP'         | ''          | ''   | '20220818'  
 '4.7UH/1.15A'                  | 'SMLF'     | 'IND'    | 'CV-4712MZ03'(!)           = ''              | ''                 | 'CV-4712MZ03'              |'L_MSCDRI-4D18C_5-1X5-1'| '4.7UH/1.15A'                  | 'DISCRETE' | 'IND SMD 4.7UH,+-20%,1.15A(MSCDRI-4D18C)'       | 'CHIP'         | ''          | ''   | '20220825'  
 '4.7UH/1.15A'                  | 'SMLF'     | 'EMPTY'  | 'CV-4712MZ03'(!)           = ''              | ''                 | 'CV-4712MZ03'              |'L_MSCDRI-4D18C_5-1X5-1'| 'NA'                           | 'IO'       | 'IND SMD 4.7UH,+-20%,1.15A(MSCDRI-4D18C)'       | 'CHIP'         | ''          | ''   | '20220825'  
 '0.18UH/60A'                   | 'SMLF'     | 'IND'    | 'CV+18^0KZ17'(!)           = ''              | ''                 | 'CV+18^0KZ17'              |'L_AF13A-120K_9-6X6-4'| '0.18UH/60A'                   | 'DISCRETE' | 'IND SMD 0.18UH 10% 60A(MSI-900609V-R18K'       | 'CHIP'         | ''          | ''   | '20220912'  
 '0.18UH/60A'                   | 'SMLF'     | 'EMPTY'  | 'CV+18^0KZ17'(!)           = ''              | ''                 | 'CV+18^0KZ17'              |'L_AF13A-120K_9-6X6-4'| 'NA'                           | 'IO'       | 'IND SMD 0.18UH 10% 60A(MSI-900609V-R18K'       | 'CHIP'         | ''          | ''   | '20220912'  
 '0.4UH/40A'                    | 'SMLF'     | 'IND'    | 'CV+40^0KZ06'(!)           = ''              | ''                 | 'CV+40^0KZ06'              |'L_HCUVD8095D-102KBQL_8X8'| '0.4UH/40A'                    | 'DISCRETE' | 'IND SMD 0.4UH 10% 40A(MSI-800810V-R40K'        | 'CHIP'         | ''          | ''   | '20220912'  
 '0.4UH/40A'                    | 'SMLF'     | 'EMPTY'  | 'CV+40^0KZ06'(!)           = ''              | ''                 | 'CV+40^0KZ06'              |'L_HCUVD8095D-102KBQL_8X8'| 'NA'                           | 'IO'       | 'IND SMD 0.4UH 10% 40A(MSI-800810V-R40K'        | 'CHIP'         | ''          | ''   | '20220912'  
 '100NH/105A'                   | 'SMLF'     | 'IND'    | 'CV+10^0EZ09'(!)           = ''              | ''                 | 'CV+10^0EZ09'              |'L_HCME706713Q-221QL_7X6-7'| '100NH/105A'                   | 'DISCRETE' | 'IND SMD 100NH 15% 105A(PGL6827.101BHLT)'       | 'CHIP'         | ''          | ''   | '20220916'  
 '100NH/105A'                   | 'SMLF'     | 'EMPTY'  | 'CV+10^0EZ09'(!)           = ''              | ''                 | 'CV+10^0EZ09'              |'L_HCME706713Q-221QL_7X6-7'| 'NA'                           | 'IO'       | 'IND SMD 100NH 15% 105A(PGL6827.101BHLT)'       | 'CHIP'         | ''          | ''   | '20220916'  
 '150NH/70A'                    | 'SMLF'     | 'IND'    | 'CV+15^0EZ15'(!)           = ''              | ''                 | 'CV+15^0EZ15'              |'L_HCME706713Q-221QL_7X6-7'| '150NH/70A'                    | 'DISCRETE' | 'IND SMD 150NH 15% 70A(PGL6827.151BHLT)'        | 'CHIP'         | ''          | ''   | '20220916'  
 '150NH/70A'                    | 'SMLF'     | 'EMPTY'  | 'CV+15^0EZ15'(!)           = ''              | ''                 | 'CV+15^0EZ15'              |'L_HCME706713Q-221QL_7X6-7'| 'NA'                           | 'IO'       | 'IND SMD 150NH 15% 70A(PGL6827.151BHLT)'        | 'CHIP'         | ''          | ''   | '20220916'  
 '100NH/105A'                   | 'SMLF'     | 'IND'    | 'CV+10^0EZ10'(!)           = ''              | ''                 | 'CV+10^0EZ10'              |'L_HCME706713Q-221QL_7X6-7'| '100NH/105A'                   | 'DISCRETE' | 'IND SMD 100NH 15% 105A(HCME706713Q-101QL'      | 'CHIP'         | ''          | ''   | '20220920'  
 '100NH/105A'                   | 'SMLF'     | 'EMPTY'  | 'CV+10^0EZ10'(!)           = ''              | ''                 | 'CV+10^0EZ10'              |'L_HCME706713Q-221QL_7X6-7'| 'NA'                           | 'IO'       | 'IND SMD 100NH 15% 105A(HCME706713Q-101QL'      | 'CHIP'         | ''          | ''   | '20220920'  
 '150NH/70A'                    | 'SMLF'     | 'IND'    | 'CV+15^0EZ16'(!)           = ''              | ''                 | 'CV+15^0EZ16'              |'L_HCME706713Q-221QL_7X6-7'| '150NH/70A'                    | 'DISCRETE' | 'IND SMD 150NH 15% 70A(HCME706713Q-151QL'       | 'CHIP'         | ''          | ''   | '20220920'  
 '150NH/70A'                    | 'SMLF'     | 'EMPTY'  | 'CV+15^0EZ16'(!)           = ''              | ''                 | 'CV+15^0EZ16'              |'L_HCME706713Q-221QL_7X6-7'| 'NA'                           | 'IO'       | 'IND SMD 150NH 15% 70A(HCME706713Q-151QL'       | 'CHIP'         | ''          | ''   | '20220920'  
 'BLM21SN300SN1D/5A'            | 'SMLF'     | 'IND'    | 'CX300SN1000'(!)           = ''              | ''                 | 'CX300SN1000'              |'L0805'| 'BLM21SN300SN1D/5A'            | 'DISCRETE' | 'EMI FILTER BLM21SN300SN1D(30,8.5A)'            | 'CHIP'         | ''          | ''   | '20221019'  
 'BLM21SN300SN1D/5A'            | 'SMLF'     | 'EMPTY'  | 'CX300SN1000'(!)           = ''              | ''                 | 'CX300SN1000'              |'L0805'| 'NA'                           | 'IO'       | 'EMI FILTER BLM21SN300SN1D(30,8.5A)'            | 'CHIP'         | ''          | ''   | '20221019'  
 'BPH853025R5V-101T/30A'        | 'SMLF'     | 'IND'    | 'CXR5V101000'(!)           = ''              | ''                 | 'CXR5V101000'              |'L_BPH853025R5V-101T_8-5X3'| 'BPH853025R5V-101T/30A'        | 'DISCRETE' | 'EMI FILTER BEAD BPH853025R5(100,30A)AEC'       | 'CHIP'         | ''          | ''   | '20221020'  
 'BPH853025R5V-101T/30A'        | 'SMLF'     | 'EMPTY'  | 'CXR5V101000'(!)           = ''              | ''                 | 'CXR5V101000'              |'L_BPH853025R5V-101T_8-5X3'| 'NA'                           | 'IO'       | 'EMI FILTER BEAD BPH853025R5(100,30A)AEC'       | 'CHIP'         | ''          | ''   | '20221020'  
 '1UH/11A'                      | 'SMLF'     | 'IND'    | 'CV-10B0MZ53'(!)           = ''              | ''                 | 'CV-10B0MZ53'              |'L_CMLE053T_4-85X4-7'| '1UH/11A'                      | 'DISCRETE' | 'IND SMD 1UH 20% 11A(PIMB053T-1R0MT-39)'        | 'CHIP'         | ''          | ''   | '20221102'  
 '1UH/11A'                      | 'SMLF'     | 'EMPTY'  | 'CV-10B0MZ53'(!)           = ''              | ''                 | 'CV-10B0MZ53'              |'L_CMLE053T_4-85X4-7'| 'NA'                           | 'IO'       | 'IND SMD 1UH 20% 11A(PIMB053T-1R0MT-39)'        | 'CHIP'         | ''          | ''   | '20221102'  
 '120NH/87A'                    | 'SMLF'     | 'IND'    | 'CV+12^0EZ14'(!)           = ''              | ''                 | 'CV+12^0EZ14'              |'L_HCME706713Q-221QL_7X6-7'| '120NH/87A'                    | 'DISCRETE' | 'IND SMD 120NH 15% 87A(PGL6827.121BHLT)'        | 'CHIP'         | ''          | ''   | '20221102'  
 '120NH/87A'                    | 'SMLF'     | 'EMPTY'  | 'CV+12^0EZ14'(!)           = ''              | ''                 | 'CV+12^0EZ14'              |'L_HCME706713Q-221QL_7X6-7'| 'NA'                           | 'IO'       | 'IND SMD 120NH 15% 87A(PGL6827.121BHLT)'        | 'CHIP'         | ''          | ''   | '20221102'  
 '120NH/88A'                    | 'SMLF'     | 'IND'    | 'CV+12^0EZ15'(!)           = ''              | ''                 | 'CV+12^0EZ15'              |'L_HCME706713Q-221QL_7X6-7'| '120NH/88A'                    | 'DISCRETE' | 'IND SMD 120NH 15% 88A(HCME706713Q-121QL)'      | 'CHIP'         | ''          | ''   | '20221115'  
 '120NH/88A'                    | 'SMLF'     | 'EMPTY'  | 'CV+12^0EZ15'(!)           = ''              | ''                 | 'CV+12^0EZ15'              |'L_HCME706713Q-221QL_7X6-7'| 'NA'                           | 'IO'       | 'IND SMD 120NH 15% 88A(HCME706713Q-121QL)'      | 'CHIP'         | ''          | ''   | '20221115'  
 '220NH/44A'                    | 'SMLF'     | 'IND'    | 'CV+22^0KZ38'(!)           = ''              | ''                 | 'CV+22^0KZ38'              |'L_AF13A-120K_9-6X6-4'| '220NH/44A'                    | 'DISCRETE' | 'IND SMD 220NH 10% 44A(HCUVE966490Q-221QL'      | 'CHIP'         | ''          | ''   | '20221121'  
 '220NH/44A'                    | 'SMLF'     | 'EMPTY'  | 'CV+22^0KZ38'(!)           = ''              | ''                 | 'CV+22^0KZ38'              |'L_AF13A-120K_9-6X6-4'| 'NA'                           | 'IO'       | 'IND SMD 220NH 10% 44A(HCUVE966490Q-221QL'      | 'CHIP'         | ''          | ''   | '20221121'  
 '0.15UH/40A'                   | 'SMLF'     | 'IND'    | 'CV+15^0MZ10'(!)           = ''              | ''                 | 'CV+15^0MZ10'              |'L_PCMB104T-R15MS0R457_11-15X10'| '0.15UH/40A'                   | 'DISCRETE' | 'IND SMD 0.15UH20%40A PCMB104T-R15MS0R457'      | 'CHIP'         | ''          | ''   | '20221128'  
 '0.15UH/40A'                   | 'SMLF'     | 'EMPTY'  | 'CV+15^0MZ10'(!)           = ''              | ''                 | 'CV+15^0MZ10'              |'L_PCMB104T-R15MS0R457_11-15X10'| 'NA'                           | 'IO'       | 'IND SMD 0.15UH20%40A PCMB104T-R15MS0R457'      | 'CHIP'         | ''          | ''   | '20221128'  
 '220NH/61A'                    | 'SMLF'     | 'IND'    | 'CV+22^0KZ40'(!)           = ''              | ''                 | 'CV+22^0KZ40'              |'L_HCUVE966412D-221'| '220NH/61A'                    | 'DISCRETE' | 'IND SMD 220NH 10% 61A(HCUVE9612Q-221QL)'       | 'CHIP'         | ''          | ''   | '20221205'  
 '220NH/61A'                    | 'SMLF'     | 'EMPTY'  | 'CV+22^0KZ40'(!)           = ''              | ''                 | 'CV+22^0KZ40'              |'L_HCUVE966412D-221'| 'NA'                           | 'IO'       | 'IND SMD 220NH 10% 61A(HCUVE9612Q-221QL)'       | 'CHIP'         | ''          | ''   | '20221205'  
 '0.33UH/82A'                   | 'SMLF'     | 'IND'    | 'CV+33^0MZ04'(!)           = ''              | ''                 | 'CV+33^0MZ04'              |'L_CMMS136E_13-45X12-6'| '0.33UH/82A'                   | 'DISCRETE' | 'IND SMD 0.33UH 20% 82A(CMMS136E-R33MSQ)'       | 'CHIP'         | ''          | ''   | '20221205'  
 '0.33UH/82A'                   | 'SMLF'     | 'EMPTY'  | 'CV+33^0MZ04'(!)           = ''              | ''                 | 'CV+33^0MZ04'              |'L_CMMS136E_13-45X12-6'| 'NA'                           | 'IO'       | 'IND SMD 0.33UH 20% 82A(CMMS136E-R33MSQ)'       | 'CHIP'         | ''          | ''   | '20221205'  
 'FB MJ1608HS220NTR/7.5A'       | 'SMLF'     | 'IND'    | 'CX000220000'(!)           = ''              | ''                 | 'CX000220000'              |'L0603_H40'| 'FB MJ1608HS220NTR/7.5A'       | 'DISCRETE' | 'EMI FILTER BEAD FBMJ1608HS220NTR(22,7.5A'      | 'CHIP'         | ''          | ''   | '20221205'  
 'FB MJ1608HS220NTR/7.5A'       | 'SMLF'     | 'EMPTY'  | 'CX000220000'(!)           = ''              | ''                 | 'CX000220000'              |'L0603_H40'| 'NA'                           | 'IO'       | 'EMI FILTER BEAD FBMJ1608HS220NTR(22,7.5A'      | 'CHIP'         | ''          | ''   | '20221205'  
 '10UH/4A'                      | 'SMLF'     | 'IND'    | 'CV01040MZ09'(!)           = ''              | ''                 | 'CV01040MZ09'              |'L_EM-100M05V05_7-2X6-6'| '10UH/4A'                      | 'DISCRETE' | 'IND SMD 10UH +-20% 4A(EM-100M05V05)'           | 'CHIP'         | ''          | ''   | '20221205'  
 '10UH/4A'                      | 'SMLF'     | 'EMPTY'  | 'CV01040MZ09'(!)           = ''              | ''                 | 'CV01040MZ09'              |'L_EM-100M05V05_7-2X6-6'| 'NA'                           | 'IO'       | 'IND SMD 10UH +-20% 4A(EM-100M05V05)'           | 'CHIP'         | ''          | ''   | '20221205'  
 '1UH/50A'                      | 'SMLF'     | 'IND'    | 'CV-10^0MZ24'(!)           = ''              | ''                 | 'CV-10^0MZ24'              |'L_ZPWM-1250M_13-5X12-8'| '1UH/50A'                      | 'DISCRETE' | 'IND SMD 1UH 20% 50A(ZPWM-1250M-1R0M)'          | 'CHIP'         | ''          | ''   | '20221205'  
 '1UH/50A'                      | 'SMLF'     | 'EMPTY'  | 'CV-10^0MZ24'(!)           = ''              | ''                 | 'CV-10^0MZ24'              |'L_ZPWM-1250M_13-5X12-8'| 'NA'                           | 'IO'       | 'IND SMD 1UH 20% 50A(ZPWM-1250M-1R0M)'          | 'CHIP'         | ''          | ''   | '20221205'  
 '0.33UH/65A'                   | 'SMLF'     | 'IND'    | 'CV+33^0MZ09'(!)           = ''              | ''                 | 'CV+33^0MZ09'              |'L_ZPWM-1250M_13-5X12-8_H256'| '0.33UH/65A'                   | 'DISCRETE' | 'IND SMD 0.33UH 20% 65A(ZPWM-1265M-R33M)'       | 'CHIP'         | ''          | ''   | '20221205'  
 '0.33UH/65A'                   | 'SMLF'     | 'EMPTY'  | 'CV+33^0MZ09'(!)           = ''              | ''                 | 'CV+33^0MZ09'              |'L_ZPWM-1250M_13-5X12-8_H256'| 'NA'                           | 'IO'       | 'IND SMD 0.33UH 20% 65A(ZPWM-1265M-R33M)'       | 'CHIP'         | ''          | ''   | '20221205'  
 '2.2UH/17A'                    | 'SMLF'     | 'IND'    | 'CV-22H0MZ04'(!)           = ''              | ''                 | 'CV-22H0MZ04'              |'L_VCMT063T-2R2MN5'| '2.2UH/17A'                    | 'DISCRETE' | 'IND SMD 2.2UH 20% 17A(ZPWM-6030DA-2R2M)'       | 'CHIP'         | ''          | ''   | '20221205'  
 '2.2UH/17A'                    | 'SMLF'     | 'EMPTY'  | 'CV-22H0MZ04'(!)           = ''              | ''                 | 'CV-22H0MZ04'              |'L_VCMT063T-2R2MN5'| 'NA'                           | 'IO'       | 'IND SMD 2.2UH 20% 17A(ZPWM-6030DA-2R2M)'       | 'CHIP'         | ''          | ''   | '20221205'  
 '220NH/65A'                    | 'SMLF'     | 'IND'    | 'CV+22^0KZ49'(!)           = ''              | ''                 | 'CV+22^0KZ49'              |'L_ZPWE-906012MA_9-6X6-6'| '220NH/65A'                    | 'DISCRETE' | 'IND SMD 220NH 10% 65A(ZPWE-906012MA-R22K'      | 'CHIP'         | ''          | ''   | '20221205'  
 '220NH/65A'                    | 'SMLF'     | 'EMPTY'  | 'CV+22^0KZ49'(!)           = ''              | ''                 | 'CV+22^0KZ49'              |'L_ZPWE-906012MA_9-6X6-6'| 'NA'                           | 'IO'       | 'IND SMD 220NH 10% 65A(ZPWE-906012MA-R22K'      | 'CHIP'         | ''          | ''   | '20221205'  
 'MHC2012S601NBP/2000MA'        | 'SMLF'     | 'IND'    | 'CX12S601004'(!)           = ''              | ''                 | 'CX12S601004'              |'L0805_H44'| 'MHC2012S601NBP/2000MA'        | 'DISCRETE' | 'EMI FILTER MHC2012S601NBP(600,2000MA)'         | 'CHIP'         | ''          | ''   | '20230109'  
 'MHC2012S601NBP/2000MA'        | 'SMLF'     | 'EMPTY'  | 'CX12S601004'(!)           = ''              | ''                 | 'CX12S601004'              |'L0805_H44'| 'NA'                           | 'IO'       | 'EMI FILTER MHC2012S601NBP(600,2000MA)'         | 'CHIP'         | ''          | ''   | '20230109'  
 'HCB2012VF-331T25/2500MA'      | 'SMLF'     | 'IND'    | 'CX331T25002'(!)           = ''              | ''                 | 'CX331T25002'              |'L0805'| 'HCB2012VF-331T25/2500MA'      | 'DISCRETE' | 'EMI FILTER HCB2012VF-331T25(330,2500MA)'       | 'CHIP'         | ''          | ''   | '20230112'  
 'HCB2012VF-331T25/2500MA'      | 'SMLF'     | 'EMPTY'  | 'CX331T25002'(!)           = ''              | ''                 | 'CX331T25002'              |'L0805'| 'NA'                           | 'IO'       | 'EMI FILTER HCB2012VF-331T25(330,2500MA)'       | 'CHIP'         | ''          | ''   | '20230112'  
 '2.2UH/13A'                    | 'SMLF'     | 'IND'    | 'CV-22D0MZ06'(!)           = ''              | ''                 | 'CV-22D0MZ06'              |'L_PCMB103T-2R2MS_10-1X10'| '2.2UH/13A'                    | 'DISCRETE' | 'IND SMD 2.2U 20%13A(PCMB103T-2R2MS)'           | 'CHIP'         | ''          | ''   | '20230111'  
 '2.2UH/13A'                    | 'SMLF'     | 'EMPTY'  | 'CV-22D0MZ06'(!)           = ''              | ''                 | 'CV-22D0MZ06'              |'L_PCMB103T-2R2MS_10-1X10'| 'NA'                           | 'IO'       | 'IND SMD 2.2U 20%13A(PCMB103T-2R2MS)'           | 'CHIP'         | ''          | ''   | '20230111'  
 '100NH/77A'                    | 'SMLF'     | 'IND'    | 'CV+10^0EZ04'(!)           = ''              | ''                 | 'CV+10^0EZ04'              |'L_HCME1012Q-121QL_10X6'| '100NH/77A'                    | 'DISCRETE' | 'IND SMD 100NH +-15% 77A(PA4990.101HLT)'        | 'CHIP'         | ''          | ''   | '20230130'  
 '100NH/77A'                    | 'SMLF'     | 'EMPTY'  | 'CV+10^0EZ04'(!)           = ''              | ''                 | 'CV+10^0EZ04'              |'L_HCME1012Q-121QL_10X6'| 'NA'                           | 'IO'       | 'IND SMD 100NH +-15% 77A(PA4990.101HLT)'        | 'CHIP'         | ''          | ''   | '20230130'  
 '400NH/21A'                    | 'SMLF'     | 'IND'    | 'CV+40L0KZ01'(!)           = ''              | ''                 | 'CV+40L0KZ01'              |'L_HCUVE966490D-121'| '400NH/21A'                    | 'DISCRETE' | 'IND SMD 400NH 10% 21A(HCUVE966490Q-401QL'      | 'CHIP'         | ''          | ''   | '20230130'  
 '400NH/21A'                    | 'SMLF'     | 'EMPTY'  | 'CV+40L0KZ01'(!)           = ''              | ''                 | 'CV+40L0KZ01'              |'L_HCUVE966490D-121'| 'NA'                           | 'IO'       | 'IND SMD 400NH 10% 21A(HCUVE966490Q-401QL'      | 'CHIP'         | ''          | ''   | '20230130'  
 '100NH/129A'                   | 'SMLF'     | 'IND'    | 'CV+10^0EZ00'(!)           = ''              | ''                 | 'CV+10^0EZ00'              |'L_L101247A-120L_10X6-4'| '100NH/129A'                   | 'DISCRETE' | 'IND SMD 100NH +-15% 129A L101247A-100L'        | 'CHIP'         | ''          | ''   | '20230130'  
 '100NH/129A'                   | 'SMLF'     | 'EMPTY'  | 'CV+10^0EZ00'(!)           = ''              | ''                 | 'CV+10^0EZ00'              |'L_L101247A-120L_10X6-4'| 'NA'                           | 'IO'       | 'IND SMD 100NH +-15% 129A L101247A-100L'        | 'CHIP'         | ''          | ''   | '20230130'  
 '0.68UH/34A'                   | 'SMLF'     | 'IND'    | 'CV+68Z0MZ03'(!)           = ''              | ''                 | 'CV+68Z0MZ03'              |'L_MMD-12EZ_13-7X12-9'| '0.68UH/34A'                   | 'DISCRETE' | 'IND SMD 0.68UH20%,34A(MMD-12EZ-R68M-V1Q)'      | 'CHIP'         | ''          | ''   | '20230208'  
 '0.68UH/34A'                   | 'SMLF'     | 'EMPTY'  | 'CV+68Z0MZ03'(!)           = ''              | ''                 | 'CV+68Z0MZ03'              |'L_MMD-12EZ_13-7X12-9'| 'NA'                           | 'IO'       | 'IND SMD 0.68UH20%,34A(MMD-12EZ-R68M-V1Q)'      | 'CHIP'         | ''          | ''   | '20230208'  
 'BLM15PG100SN1D/1000MA'        | 'SMLF'     | 'IND'    | 'CX5PG100000'(!)           = ''              | ''               | 'CX5PG100000'              |'L0402'| 'BLM15PG100SN1D/1000MA'        | 'DISCRETE' | 'EMI FILTER BLM15PG100SN1D(10,1000MA)'          | 'CHIP'         | ''          | ''   | '20230213'  
 'BLM15PG100SN1D/1000MA'        | 'SMLF'     | 'EMPTY'  | 'CX5PG100000'(!)           = ''              | ''               | 'CX5PG100000'              |'L0402'| 'NA'                           | 'IO'       | 'EMI FILTER BLM15PG100SN1D(10,1000MA)'          | 'CHIP'         | ''          | ''   | '20230213'  

END_PART

END.

